FILE_TYPE = MACRO_DRAWING;
SET COLOR_WIRE YELLOW;
SET COLOR_PROP ORANGE;
SET COLOR_DOT WHITE;
SET COLOR_ARC YELLOW;
SET COLOR_BODY GREEN;
SET COLOR_NOTE PURPLE;
SET PROP_DISPLAY VALUE;
SET PAGE_NUMBER P270;
FORCEADD OFFPAGE..1
(-4100 -2075);
FORCEPROP 2 LAST $XR6 290 
J 0
(-4352 -2039);
DISPLAY 0.638298 (-4352 -2039);
PAINT MONO (-4352 -2039);
FORCEPROP 2 LAST $XR5 289 
J 0
(-4592 -2111);
DISPLAY 0.638298 (-4592 -2111);
PAINT MONO (-4592 -2111);
FORCEPROP 2 LAST $XR4 288 
J 0
(-4472 -2111);
DISPLAY 0.638298 (-4472 -2111);
PAINT MONO (-4472 -2111);
FORCEPROP 2 LAST $XR3 287 
J 0
(-4352 -2111);
DISPLAY 0.638298 (-4352 -2111);
PAINT MONO (-4352 -2111);
FORCEPROP 2 LAST $XR2 286 
J 0
(-4592 -2075);
DISPLAY 0.638298 (-4592 -2075);
PAINT MONO (-4592 -2075);
FORCEPROP 2 LAST $XR1 285 
J 0
(-4472 -2075);
DISPLAY 0.638298 (-4472 -2075);
PAINT MONO (-4472 -2075);
FORCEPROP 2 LAST $XR0 284 
J 0
(-4352 -2075);
DISPLAY 0.638298 (-4352 -2075);
PAINT MONO (-4352 -2075);
FORCEPROP 1 LAST COMMENT_BODY TRUE
J 0
(-3975 -2175);
DISPLAY 0.872340 (-3975 -2175);
PAINT GREEN (-3975 -2175);
DISPLAY INVISIBLE (-3975 -2175);
FORCEPROP 1 LAST OFFPAGE TRUE
J 0
(-3775 -2200);
DISPLAY 0.872340 (-3775 -2200);
PAINT GREEN (-3775 -2200);
DISPLAY INVISIBLE (-3775 -2200);
FORCEPROP 2 LAST CDS_LIB standard
J 0
(-4100 -2075);
DISPLAY INVISIBLE (-4100 -2075);
FORCEPROP 2 LAST PATH I1
J 0
(-4350 -2000);
DISPLAY 1.021277 (-4350 -2000);
DISPLAY INVISIBLE (-4350 -2000);
FORCEADD OFFPAGE..5
(-3200 -1775);
FORCEPROP 2 LAST $XR1 254 
J 0
(-3575 -1775);
DISPLAY 0.638298 (-3575 -1775);
PAINT MONO (-3575 -1775);
FORCEPROP 2 LAST $XR0 214 
J 0
(-3455 -1775);
DISPLAY 0.638298 (-3455 -1775);
PAINT MONO (-3455 -1775);
FORCEPROP 1 LAST COMMENT_BODY TRUE
J 0
(-3100 -1850);
DISPLAY 0.872340 (-3100 -1850);
PAINT GREEN (-3100 -1850);
DISPLAY INVISIBLE (-3100 -1850);
FORCEPROP 1 LAST OFFPAGE TRUE
J 0
(-2875 -1900);
DISPLAY 0.872340 (-2875 -1900);
PAINT GREEN (-2875 -1900);
DISPLAY INVISIBLE (-2875 -1900);
FORCEPROP 2 LAST CDS_LIB standard
J 0
(-3200 -1775);
DISPLAY INVISIBLE (-3200 -1775);
FORCEPROP 2 LAST PATH I10
J 0
(-3450 -1725);
DISPLAY 1.021277 (-3450 -1725);
DISPLAY INVISIBLE (-3450 -1725);
FORCEADD Q_RES..1
(3925 -1075);
FORCEPROP 1 LAST PART_NUMBER CS04992FB07
J 0
(4050 -1025);
DISPLAY 0.617021 (4050 -1025);
PAINT BLUE (4050 -1025);
DISPLAY INVISIBLE (4050 -1025);
FORCEPROP 1 LAST MATERIAL CHIP
J 0
(4300 -1075);
DISPLAY 0.617021 (4300 -1075);
PAINT SKYBLUE (4300 -1075);
FORCEPROP 1 LAST VALUE 49.9
J 2
(4150 -1075);
DISPLAY 0.617021 (4150 -1075);
PAINT SKYBLUE (4150 -1075);
FORCEPROP 1 LAST TOLERANCE 1%
J 0
(4200 -1075);
DISPLAY 0.617021 (4200 -1075);
PAINT SKYBLUE (4200 -1075);
FORCEPROP 1 LAST LOCATION R2554
J 0
(3700 -1075);
DISPLAY 0.617021 (3700 -1075);
PAINT AQUA (3700 -1075);
FORCEPROP 1 LASTPIN (3825 -1075) $PN 1
J 0
(3837 -1063);
DISPLAY 0.617021 (3837 -1063);
FORCEPROP 1 LASTPIN (4025 -1075) $PN 2
J 0
(3987 -1063);
DISPLAY 0.617021 (3987 -1063);
FORCEPROP 1 LAST PACK_TYPE 0402LF
J 0
(4050 -975);
DISPLAY 0.617021 (4050 -975);
PAINT SKYBLUE (4050 -975);
DISPLAY INVISIBLE (4050 -975);
FORCEPROP 1 LAST WATTAGE 1/16W
J 2
(4400 -975);
DISPLAY 0.617021 (4400 -975);
PAINT SKYBLUE (4400 -975);
DISPLAY INVISIBLE (4400 -975);
FORCEPROP 2 LAST CDS_LIB pure_quanta
J 0
(3925 -1075);
PAINT MONO (3925 -1075);
DISPLAY INVISIBLE (3925 -1075);
FORCEPROP 1 LAST PATH I100
J 0
(3875 -925);
DISPLAY 0.978723 (3875 -925);
PAINT WHITE (3875 -925);
DISPLAY INVISIBLE (3875 -925);
FORCEPROP 2 LAST $SEC 1
J 0
(3875 -875);
DISPLAY 0.680851 (3875 -875);
PAINT MONO (3875 -875);
DISPLAY INVISIBLE (3875 -875);
FORCEPROP 2 LAST CDS_SEC 1
J 0
(3875 -875);
DISPLAY 1.021277 (3875 -875);
DISPLAY INVISIBLE (3875 -875);
FORCEADD Q_RES..1
(3925 -1225);
FORCEPROP 1 LAST PART_NUMBER CS04992FB07
J 0
(4050 -1175);
DISPLAY 0.617021 (4050 -1175);
PAINT BLUE (4050 -1175);
DISPLAY INVISIBLE (4050 -1175);
FORCEPROP 1 LAST TOLERANCE 1%
J 0
(4200 -1225);
DISPLAY 0.617021 (4200 -1225);
PAINT SKYBLUE (4200 -1225);
FORCEPROP 1 LAST MATERIAL EMPTY
J 0
(4300 -1225);
DISPLAY 0.617021 (4300 -1225);
PAINT RED (4300 -1225);
FORCEPROP 1 LAST VALUE 49.9
J 2
(4150 -1225);
DISPLAY 0.617021 (4150 -1225);
PAINT SKYBLUE (4150 -1225);
FORCEPROP 1 LAST LOCATION R2555
J 0
(3700 -1225);
DISPLAY 0.617021 (3700 -1225);
PAINT AQUA (3700 -1225);
FORCEPROP 1 LASTPIN (3825 -1225) $PN 1
J 0
(3837 -1213);
DISPLAY 0.617021 (3837 -1213);
FORCEPROP 1 LASTPIN (4025 -1225) $PN 2
J 0
(3987 -1213);
DISPLAY 0.617021 (3987 -1213);
FORCEPROP 1 LAST PACK_TYPE 0402LF
J 0
(4050 -1125);
DISPLAY 0.617021 (4050 -1125);
PAINT SKYBLUE (4050 -1125);
DISPLAY INVISIBLE (4050 -1125);
FORCEPROP 1 LAST WATTAGE 1/16W
J 2
(4400 -1125);
DISPLAY 0.617021 (4400 -1125);
PAINT SKYBLUE (4400 -1125);
DISPLAY INVISIBLE (4400 -1125);
FORCEPROP 2 LAST CDS_LIB pure_quanta
J 0
(3925 -1225);
PAINT MONO (3925 -1225);
DISPLAY INVISIBLE (3925 -1225);
FORCEPROP 1 LAST PATH I101
J 0
(3875 -1075);
DISPLAY 0.978723 (3875 -1075);
PAINT WHITE (3875 -1075);
DISPLAY INVISIBLE (3875 -1075);
FORCEPROP 2 LAST $SEC 1
J 0
(3875 -1025);
DISPLAY 0.680851 (3875 -1025);
PAINT MONO (3875 -1025);
DISPLAY INVISIBLE (3875 -1025);
FORCEPROP 2 LAST CDS_SEC 1
J 0
(3875 -1025);
DISPLAY 1.021277 (3875 -1025);
DISPLAY INVISIBLE (3875 -1025);
FORCEADD UNIVERSAL_GND..1
(3700 -600);
FORCEPROP 3 LASTPIN (3700 -550) SIG_NAME GND\g
J 0
(3710 -540);
DISPLAY 0.659574 (3710 -540);
PAINT MONO (3710 -540);
DISPLAY INVISIBLE (3710 -540);
FORCEPROP 1 LAST HDL_POWER GND
J 1
(3725 -675);
DISPLAY 0.872340 (3725 -675);
PAINT GREEN (3725 -675);
DISPLAY INVISIBLE (3725 -675);
FORCEPROP 2 LAST CDS_LIB logical_power
J 0
(3700 -600);
PAINT MONO (3700 -600);
DISPLAY INVISIBLE (3700 -600);
FORCEPROP 1 LAST PATH I102
J 0
(3775 -600);
DISPLAY 0.872340 (3775 -600);
PAINT AQUA (3775 -600);
DISPLAY INVISIBLE (3775 -600);
FORCEADD Q_CAP..1
(3700 -300);
FORCEPROP 1 LAST PART_NUMBER CH610KME907
J 0
(3750 -500);
DISPLAY 0.617021 (3750 -500);
PAINT BLUE (3750 -500);
DISPLAY INVISIBLE (3750 -500);
FORCEPROP 1 LAST MATERIAL EMPTY
J 0
(3750 -400);
DISPLAY 0.617021 (3750 -400);
PAINT RED (3750 -400);
FORCEPROP 1 LAST TOLERANCE 20%
J 0
(3750 -350);
DISPLAY 0.617021 (3750 -350);
PAINT SKYBLUE (3750 -350);
FORCEPROP 1 LAST VALUE 10UF
J 0
(3750 -250);
DISPLAY 0.617021 (3750 -250);
PAINT SKYBLUE (3750 -250);
FORCEPROP 1 LAST VOLTAGE 4V
J 0
(3750 -300);
DISPLAY 0.617021 (3750 -300);
PAINT SKYBLUE (3750 -300);
FORCEPROP 1 LAST PACK_TYPE C0603
J 0
(3750 -450);
DISPLAY 0.617021 (3750 -450);
PAINT SKYBLUE (3750 -450);
FORCEPROP 1 LAST LOCATION C2448
J 0
(3750 -200);
DISPLAY 0.617021 (3750 -200);
PAINT AQUA (3750 -200);
FORCEPROP 1 LASTPIN (3700 -200) $PN 1
J 0
(3710 -220);
DISPLAY 0.617021 (3710 -220);
PAINT MONO (3710 -220);
FORCEPROP 1 LASTPIN (3700 -400) $PN 2
J 0
(3710 -420);
DISPLAY 0.617021 (3710 -420);
PAINT MONO (3710 -420);
FORCEPROP 2 LAST CDS_LIB pure_quanta
J 0
(3700 -300);
DISPLAY INVISIBLE (3700 -300);
FORCEPROP 1 LAST PATH I103
J 0
(3750 -150);
DISPLAY 0.978723 (3750 -150);
PAINT WHITE (3750 -150);
DISPLAY INVISIBLE (3750 -150);
FORCEPROP 1 LAST LOCATION C2448
J 0
(3750 -150);
DISPLAY 1.021277 (3750 -150);
PAINT AQUA (3750 -150);
DISPLAY INVISIBLE (3750 -150);
FORCEPROP 0 LAST $SEC 1
J 0
(3750 -150);
DISPLAY 0.680851 (3750 -150);
PAINT MONO (3750 -150);
DISPLAY INVISIBLE (3750 -150);
FORCEPROP 0 LAST CDS_SEC 1
J 0
(3750 -150);
DISPLAY 1.021277 (3750 -150);
DISPLAY INVISIBLE (3750 -150);
FORCEADD Q_CAP..1
(4025 -325);
FORCEPROP 1 LAST PART_NUMBER CH4106K1B01
J 0
(4100 -500);
DISPLAY 0.617021 (4100 -500);
PAINT BLUE (4100 -500);
DISPLAY INVISIBLE (4100 -500);
FORCEPROP 1 LAST TOLERANCE 10%
J 0
(4100 -350);
DISPLAY 0.617021 (4100 -350);
PAINT SKYBLUE (4100 -350);
FORCEPROP 1 LAST MATERIAL X7R
J 0
(4100 -400);
DISPLAY 0.617021 (4100 -400);
PAINT SKYBLUE (4100 -400);
FORCEPROP 1 LAST PACK_TYPE C0402
J 0
(4100 -450);
DISPLAY 0.617021 (4100 -450);
PAINT SKYBLUE (4100 -450);
FORCEPROP 1 LAST VOLTAGE 50V
J 0
(4100 -300);
DISPLAY 0.617021 (4100 -300);
PAINT SKYBLUE (4100 -300);
FORCEPROP 1 LAST VALUE 100NF
J 0
(4100 -250);
DISPLAY 0.617021 (4100 -250);
PAINT SKYBLUE (4100 -250);
FORCEPROP 1 LAST LOCATION C2449
J 0
(4100 -200);
DISPLAY 0.617021 (4100 -200);
PAINT AQUA (4100 -200);
FORCEPROP 1 LASTPIN (4025 -225) $PN 1
J 0
(4035 -245);
DISPLAY 0.617021 (4035 -245);
PAINT MONO (4035 -245);
FORCEPROP 1 LASTPIN (4025 -425) $PN 2
J 0
(4035 -445);
DISPLAY 0.617021 (4035 -445);
PAINT MONO (4035 -445);
FORCEPROP 2 LAST CDS_LIB pure_quanta
J 0
(4025 -325);
DISPLAY INVISIBLE (4025 -325);
FORCEPROP 1 LAST PATH I104
J 0
(4075 -175);
DISPLAY 0.978723 (4075 -175);
PAINT WHITE (4075 -175);
DISPLAY INVISIBLE (4075 -175);
FORCEPROP 1 LAST LOCATION C2449
J 0
(4075 -125);
DISPLAY 1.021277 (4075 -125);
PAINT AQUA (4075 -125);
DISPLAY INVISIBLE (4075 -125);
FORCEPROP 0 LAST $SEC 1
J 0
(4075 -125);
DISPLAY 0.680851 (4075 -125);
PAINT MONO (4075 -125);
DISPLAY INVISIBLE (4075 -125);
FORCEPROP 0 LAST CDS_SEC 1
J 0
(4075 -125);
DISPLAY 1.021277 (4075 -125);
DISPLAY INVISIBLE (4075 -125);
FORCEADD VCC15..1
(4425 -25);
FORCEPROP 3 LASTPIN (4425 -75) SIG_NAME PVNN_TERM_CPU1\g
J 0
(4435 -65);
DISPLAY 0.659574 (4435 -65);
PAINT MONO (4435 -65);
DISPLAY INVISIBLE (4435 -65);
FORCEPROP 1 LAST HDL_POWER PVNN_TERM_CPU1
J 1
(4425 25);
DISPLAY 0.617021 (4425 25);
PAINT GREEN (4425 25);
FORCEPROP 2 LAST CDS_LIB logical_power
J 0
(4425 -25);
DISPLAY INVISIBLE (4425 -25);
FORCEPROP 1 LAST PATH I105
J 0
(4475 0);
DISPLAY 0.872340 (4475 0);
PAINT AQUA (4475 0);
DISPLAY INVISIBLE (4475 0);
FORCEADD OFFPAGE..2
(2000 225);
FORCEPROP 2 LAST $XR0 288 
J 0
(2189 225);
DISPLAY 0.638298 (2189 225);
PAINT MONO (2189 225);
FORCEPROP 1 LAST COMMENT_BODY TRUE
J 0
(1955 130);
DISPLAY 0.872340 (1955 130);
PAINT GREEN (1955 130);
DISPLAY INVISIBLE (1955 130);
FORCEPROP 1 LAST OFFPAGE TRUE
J 0
(2325 100);
DISPLAY 0.872340 (2325 100);
PAINT GREEN (2325 100);
DISPLAY INVISIBLE (2325 100);
FORCEPROP 2 LAST CDS_LIB standard
J 0
(2000 225);
DISPLAY INVISIBLE (2000 225);
FORCEPROP 2 LAST PATH I106
J 0
(2200 275);
DISPLAY 1.021277 (2200 275);
DISPLAY INVISIBLE (2200 275);
FORCEADD OFFPAGE..4
(2000 425);
FORCEPROP 2 LAST $XR0 287 
J 0
(2186 425);
DISPLAY 0.638298 (2186 425);
PAINT MONO (2186 425);
FORCEPROP 1 LAST COMMENT_BODY TRUE
J 0
(1975 325);
DISPLAY 0.872340 (1975 325);
PAINT GREEN (1975 325);
DISPLAY INVISIBLE (1975 325);
FORCEPROP 1 LAST OFFPAGE TRUE
J 0
(2325 300);
DISPLAY 0.872340 (2325 300);
PAINT GREEN (2325 300);
DISPLAY INVISIBLE (2325 300);
FORCEPROP 2 LAST CDS_LIB standard
J 0
(2000 425);
DISPLAY INVISIBLE (2000 425);
FORCEPROP 2 LAST PATH I107
J 0
(2200 475);
DISPLAY 1.021277 (2200 475);
DISPLAY INVISIBLE (2200 475);
FORCEADD OFFPAGE..2
(2000 525);
FORCEPROP 2 LAST $XR0 287 
J 0
(2189 525);
DISPLAY 0.638298 (2189 525);
PAINT MONO (2189 525);
FORCEPROP 1 LAST COMMENT_BODY TRUE
J 0
(1955 430);
DISPLAY 0.872340 (1955 430);
PAINT GREEN (1955 430);
DISPLAY INVISIBLE (1955 430);
FORCEPROP 1 LAST OFFPAGE TRUE
J 0
(2325 400);
DISPLAY 0.872340 (2325 400);
PAINT GREEN (2325 400);
DISPLAY INVISIBLE (2325 400);
FORCEPROP 2 LAST CDS_LIB standard
J 0
(2000 525);
DISPLAY INVISIBLE (2000 525);
FORCEPROP 2 LAST PATH I108
J 0
(2200 575);
DISPLAY 1.021277 (2200 575);
DISPLAY INVISIBLE (2200 575);
FORCEADD OFFPAGE..4
(2000 725);
FORCEPROP 2 LAST $XR0 287 
J 0
(2186 725);
DISPLAY 0.638298 (2186 725);
PAINT MONO (2186 725);
FORCEPROP 1 LAST COMMENT_BODY TRUE
J 0
(1975 625);
DISPLAY 0.872340 (1975 625);
PAINT GREEN (1975 625);
DISPLAY INVISIBLE (1975 625);
FORCEPROP 1 LAST OFFPAGE TRUE
J 0
(2325 600);
DISPLAY 0.872340 (2325 600);
PAINT GREEN (2325 600);
DISPLAY INVISIBLE (2325 600);
FORCEPROP 2 LAST CDS_LIB standard
J 0
(2000 725);
DISPLAY INVISIBLE (2000 725);
FORCEPROP 2 LAST PATH I109
J 0
(2200 775);
DISPLAY 1.021277 (2200 775);
DISPLAY INVISIBLE (2200 775);
FORCEADD OFFPAGE..1
(-3200 -1375);
FORCEPROP 2 LAST $XR0 222 
J 0
(-3452 -1375);
DISPLAY 0.638298 (-3452 -1375);
PAINT MONO (-3452 -1375);
FORCEPROP 1 LAST COMMENT_BODY TRUE
J 0
(-3075 -1475);
DISPLAY 0.872340 (-3075 -1475);
PAINT GREEN (-3075 -1475);
DISPLAY INVISIBLE (-3075 -1475);
FORCEPROP 1 LAST OFFPAGE TRUE
J 0
(-2875 -1500);
DISPLAY 0.872340 (-2875 -1500);
PAINT GREEN (-2875 -1500);
DISPLAY INVISIBLE (-2875 -1500);
FORCEPROP 2 LAST CDS_LIB standard
J 0
(-3200 -1375);
DISPLAY INVISIBLE (-3200 -1375);
FORCEPROP 2 LAST PATH I11
J 0
(-3450 -1325);
DISPLAY 1.021277 (-3450 -1325);
DISPLAY INVISIBLE (-3450 -1325);
FORCEADD OFFPAGE..2
(2000 825);
FORCEPROP 2 LAST $XR0 287 
J 0
(2189 825);
DISPLAY 0.638298 (2189 825);
PAINT MONO (2189 825);
FORCEPROP 1 LAST COMMENT_BODY TRUE
J 0
(1955 730);
DISPLAY 0.872340 (1955 730);
PAINT GREEN (1955 730);
DISPLAY INVISIBLE (1955 730);
FORCEPROP 1 LAST OFFPAGE TRUE
J 0
(2325 700);
DISPLAY 0.872340 (2325 700);
PAINT GREEN (2325 700);
DISPLAY INVISIBLE (2325 700);
FORCEPROP 2 LAST CDS_LIB standard
J 0
(2000 825);
DISPLAY INVISIBLE (2000 825);
FORCEPROP 2 LAST PATH I110
J 0
(2200 875);
DISPLAY 1.021277 (2200 875);
DISPLAY INVISIBLE (2200 875);
FORCEADD OFFPAGE..4
(2000 1025);
FORCEPROP 2 LAST $XR0 286 
J 0
(2186 1025);
DISPLAY 0.638298 (2186 1025);
PAINT MONO (2186 1025);
FORCEPROP 1 LAST COMMENT_BODY TRUE
J 0
(1975 925);
DISPLAY 0.872340 (1975 925);
PAINT GREEN (1975 925);
DISPLAY INVISIBLE (1975 925);
FORCEPROP 1 LAST OFFPAGE TRUE
J 0
(2325 900);
DISPLAY 0.872340 (2325 900);
PAINT GREEN (2325 900);
DISPLAY INVISIBLE (2325 900);
FORCEPROP 2 LAST CDS_LIB standard
J 0
(2000 1025);
DISPLAY INVISIBLE (2000 1025);
FORCEPROP 2 LAST PATH I111
J 0
(2200 1075);
DISPLAY 1.021277 (2200 1075);
DISPLAY INVISIBLE (2200 1075);
FORCEADD OFFPAGE..2
(2000 1125);
FORCEPROP 2 LAST $XR0 286 
J 0
(2189 1125);
DISPLAY 0.638298 (2189 1125);
PAINT MONO (2189 1125);
FORCEPROP 1 LAST COMMENT_BODY TRUE
J 0
(1955 1030);
DISPLAY 0.872340 (1955 1030);
PAINT GREEN (1955 1030);
DISPLAY INVISIBLE (1955 1030);
FORCEPROP 1 LAST OFFPAGE TRUE
J 0
(2325 1000);
DISPLAY 0.872340 (2325 1000);
PAINT GREEN (2325 1000);
DISPLAY INVISIBLE (2325 1000);
FORCEPROP 2 LAST CDS_LIB standard
J 0
(2000 1125);
DISPLAY INVISIBLE (2000 1125);
FORCEPROP 2 LAST PATH I112
J 0
(2200 1175);
DISPLAY 1.021277 (2200 1175);
DISPLAY INVISIBLE (2200 1175);
FORCEADD OFFPAGE..4
(2000 1325);
FORCEPROP 2 LAST $XR0 286 
J 0
(2186 1325);
DISPLAY 0.638298 (2186 1325);
PAINT MONO (2186 1325);
FORCEPROP 1 LAST COMMENT_BODY TRUE
J 0
(1975 1225);
DISPLAY 0.872340 (1975 1225);
PAINT GREEN (1975 1225);
DISPLAY INVISIBLE (1975 1225);
FORCEPROP 1 LAST OFFPAGE TRUE
J 0
(2325 1200);
DISPLAY 0.872340 (2325 1200);
PAINT GREEN (2325 1200);
DISPLAY INVISIBLE (2325 1200);
FORCEPROP 2 LAST CDS_LIB standard
J 0
(2000 1325);
DISPLAY INVISIBLE (2000 1325);
FORCEPROP 2 LAST PATH I113
J 0
(2200 1375);
DISPLAY 1.021277 (2200 1375);
DISPLAY INVISIBLE (2200 1375);
FORCEADD OFFPAGE..2
(2000 1425);
FORCEPROP 2 LAST $XR0 286 
J 0
(2189 1425);
DISPLAY 0.638298 (2189 1425);
PAINT MONO (2189 1425);
FORCEPROP 1 LAST COMMENT_BODY TRUE
J 0
(1955 1330);
DISPLAY 0.872340 (1955 1330);
PAINT GREEN (1955 1330);
DISPLAY INVISIBLE (1955 1330);
FORCEPROP 1 LAST OFFPAGE TRUE
J 0
(2325 1300);
DISPLAY 0.872340 (2325 1300);
PAINT GREEN (2325 1300);
DISPLAY INVISIBLE (2325 1300);
FORCEPROP 2 LAST CDS_LIB standard
J 0
(2000 1425);
DISPLAY INVISIBLE (2000 1425);
FORCEPROP 2 LAST PATH I114
J 0
(2200 1475);
DISPLAY 1.021277 (2200 1475);
DISPLAY INVISIBLE (2200 1475);
FORCEADD OFFPAGE..4
(2000 1625);
FORCEPROP 2 LAST $XR0 285 
J 0
(2186 1625);
DISPLAY 0.638298 (2186 1625);
PAINT MONO (2186 1625);
FORCEPROP 1 LAST COMMENT_BODY TRUE
J 0
(1975 1525);
DISPLAY 0.872340 (1975 1525);
PAINT GREEN (1975 1525);
DISPLAY INVISIBLE (1975 1525);
FORCEPROP 1 LAST OFFPAGE TRUE
J 0
(2325 1500);
DISPLAY 0.872340 (2325 1500);
PAINT GREEN (2325 1500);
DISPLAY INVISIBLE (2325 1500);
FORCEPROP 2 LAST CDS_LIB standard
J 0
(2000 1625);
DISPLAY INVISIBLE (2000 1625);
FORCEPROP 2 LAST PATH I115
J 0
(2200 1675);
DISPLAY 1.021277 (2200 1675);
DISPLAY INVISIBLE (2200 1675);
FORCEADD OFFPAGE..2
(2000 1725);
FORCEPROP 2 LAST $XR0 285 
J 0
(2189 1725);
DISPLAY 0.638298 (2189 1725);
PAINT MONO (2189 1725);
FORCEPROP 1 LAST COMMENT_BODY TRUE
J 0
(1955 1630);
DISPLAY 0.872340 (1955 1630);
PAINT GREEN (1955 1630);
DISPLAY INVISIBLE (1955 1630);
FORCEPROP 1 LAST OFFPAGE TRUE
J 0
(2325 1600);
DISPLAY 0.872340 (2325 1600);
PAINT GREEN (2325 1600);
DISPLAY INVISIBLE (2325 1600);
FORCEPROP 2 LAST CDS_LIB standard
J 0
(2000 1725);
DISPLAY INVISIBLE (2000 1725);
FORCEPROP 2 LAST PATH I116
J 0
(2200 1775);
DISPLAY 1.021277 (2200 1775);
DISPLAY INVISIBLE (2200 1775);
FORCEADD OFFPAGE..4
(2000 1925);
FORCEPROP 2 LAST $XR0 285 
J 0
(2186 1925);
DISPLAY 0.638298 (2186 1925);
PAINT MONO (2186 1925);
FORCEPROP 1 LAST COMMENT_BODY TRUE
J 0
(1975 1825);
DISPLAY 0.872340 (1975 1825);
PAINT GREEN (1975 1825);
DISPLAY INVISIBLE (1975 1825);
FORCEPROP 1 LAST OFFPAGE TRUE
J 0
(2325 1800);
DISPLAY 0.872340 (2325 1800);
PAINT GREEN (2325 1800);
DISPLAY INVISIBLE (2325 1800);
FORCEPROP 2 LAST CDS_LIB standard
J 0
(2000 1925);
DISPLAY INVISIBLE (2000 1925);
FORCEPROP 2 LAST PATH I117
J 0
(2200 1975);
DISPLAY 1.021277 (2200 1975);
DISPLAY INVISIBLE (2200 1975);
FORCEADD OFFPAGE..2
(2000 2025);
FORCEPROP 2 LAST $XR0 285 
J 0
(2189 2025);
DISPLAY 0.638298 (2189 2025);
PAINT MONO (2189 2025);
FORCEPROP 1 LAST COMMENT_BODY TRUE
J 0
(1955 1930);
DISPLAY 0.872340 (1955 1930);
PAINT GREEN (1955 1930);
DISPLAY INVISIBLE (1955 1930);
FORCEPROP 1 LAST OFFPAGE TRUE
J 0
(2325 1900);
DISPLAY 0.872340 (2325 1900);
PAINT GREEN (2325 1900);
DISPLAY INVISIBLE (2325 1900);
FORCEPROP 2 LAST CDS_LIB standard
J 0
(2000 2025);
DISPLAY INVISIBLE (2000 2025);
FORCEPROP 2 LAST PATH I118
J 0
(2200 2075);
DISPLAY 1.021277 (2200 2075);
DISPLAY INVISIBLE (2200 2075);
FORCEADD Q_CAP..1
(1450 2350);
FORCEPROP 1 LAST PART_NUMBER CH6101MEB03
J 0
(1500 2175);
DISPLAY 0.617021 (1500 2175);
PAINT BLUE (1500 2175);
DISPLAY INVISIBLE (1500 2175);
FORCEPROP 1 LAST VOLTAGE 6.3V
J 0
(1500 2375);
DISPLAY 0.617021 (1500 2375);
PAINT SKYBLUE (1500 2375);
FORCEPROP 1 LAST TOLERANCE 20%
J 0
(1500 2325);
DISPLAY 0.617021 (1500 2325);
PAINT SKYBLUE (1500 2325);
FORCEPROP 1 LAST MATERIAL X6S
J 0
(1500 2275);
DISPLAY 0.617021 (1500 2275);
PAINT SKYBLUE (1500 2275);
FORCEPROP 1 LAST PACK_TYPE C0402
J 0
(1500 2225);
DISPLAY 0.617021 (1500 2225);
PAINT SKYBLUE (1500 2225);
FORCEPROP 1 LAST VALUE 10UF
J 0
(1500 2425);
DISPLAY 0.617021 (1500 2425);
PAINT SKYBLUE (1500 2425);
FORCEPROP 1 LAST LOCATION PC553
J 0
(1500 2475);
DISPLAY 0.617021 (1500 2475);
PAINT AQUA (1500 2475);
FORCEPROP 1 LASTPIN (1450 2450) $PN 1
J 0
(1460 2430);
DISPLAY 0.617021 (1460 2430);
PAINT MONO (1460 2430);
FORCEPROP 1 LASTPIN (1450 2250) $PN 2
J 0
(1460 2230);
DISPLAY 0.617021 (1460 2230);
PAINT MONO (1460 2230);
FORCEPROP 2 LAST CDS_LIB pure_quanta
J 0
(1450 2350);
DISPLAY INVISIBLE (1450 2350);
FORCEPROP 1 LAST PATH I119
J 0
(1500 2500);
DISPLAY 0.978723 (1500 2500);
PAINT WHITE (1500 2500);
DISPLAY INVISIBLE (1500 2500);
FORCEPROP 1 LAST LOCATION PC553
J 0
(1500 2525);
DISPLAY 1.021277 (1500 2525);
PAINT AQUA (1500 2525);
DISPLAY INVISIBLE (1500 2525);
FORCEPROP 0 LAST $SEC 1
J 0
(1500 2525);
DISPLAY 0.680851 (1500 2525);
PAINT MONO (1500 2525);
DISPLAY INVISIBLE (1500 2525);
FORCEPROP 0 LAST CDS_SEC 1
J 0
(1500 2525);
DISPLAY 1.021277 (1500 2525);
DISPLAY INVISIBLE (1500 2525);
FORCEADD Q_RES..1
(-3100 -600);
FORCEPROP 1 LAST PART_NUMBER CS11002FB07
J 0
(-3175 -550);
DISPLAY 0.489362 (-3175 -550);
PAINT BLUE (-3175 -550);
DISPLAY INVISIBLE (-3175 -550);
FORCEPROP 1 LAST MATERIAL CHIP
J 0
(-3175 -500);
DISPLAY 0.489362 (-3175 -500);
PAINT SKYBLUE (-3175 -500);
FORCEPROP 1 LAST TOLERANCE 1%
J 0
(-2875 -600);
DISPLAY 0.617021 (-2875 -600);
PAINT SKYBLUE (-2875 -600);
FORCEPROP 1 LAST VALUE 100
J 2
(-2900 -600);
DISPLAY 0.617021 (-2900 -600);
PAINT SKYBLUE (-2900 -600);
FORCEPROP 1 LAST WATTAGE 1/16W
J 2
(-2925 -500);
DISPLAY 0.489362 (-2925 -500);
PAINT SKYBLUE (-2925 -500);
FORCEPROP 1 LAST PACK_TYPE 0402LF
J 0
(-2800 -600);
DISPLAY 0.617021 (-2800 -600);
PAINT SKYBLUE (-2800 -600);
FORCEPROP 1 LAST LOCATION PR560
J 0
(-3300 -600);
DISPLAY 0.617021 (-3300 -600);
PAINT AQUA (-3300 -600);
FORCEPROP 1 LASTPIN (-3200 -600) $PN 1
J 0
(-3188 -588);
DISPLAY 0.617021 (-3188 -588);
FORCEPROP 1 LASTPIN (-3000 -600) $PN 2
J 0
(-3038 -588);
DISPLAY 0.617021 (-3038 -588);
FORCEPROP 2 LAST CDS_LIB pure_quanta
J 0
(-3100 -600);
PAINT MONO (-3100 -600);
DISPLAY INVISIBLE (-3100 -600);
FORCEPROP 1 LAST PATH I12
J 0
(-3150 -450);
DISPLAY 0.978723 (-3150 -450);
PAINT WHITE (-3150 -450);
DISPLAY INVISIBLE (-3150 -450);
FORCEPROP 2 LAST $SEC 1
J 0
(-3150 -400);
DISPLAY 0.680851 (-3150 -400);
PAINT MONO (-3150 -400);
DISPLAY INVISIBLE (-3150 -400);
FORCEPROP 2 LAST CDS_SEC 1
J 0
(-3150 -400);
DISPLAY 1.021277 (-3150 -400);
DISPLAY INVISIBLE (-3150 -400);
FORCEADD Q_CAP..1
(1450 2825);
FORCEPROP 1 LAST PART_NUMBER CH4106K1B01
J 0
(1500 2650);
DISPLAY 0.617021 (1500 2650);
PAINT BLUE (1500 2650);
DISPLAY INVISIBLE (1500 2650);
FORCEPROP 1 LAST VALUE 100NF
J 0
(1500 2900);
DISPLAY 0.617021 (1500 2900);
PAINT SKYBLUE (1500 2900);
FORCEPROP 1 LAST VOLTAGE 50V
J 0
(1500 2850);
DISPLAY 0.617021 (1500 2850);
PAINT SKYBLUE (1500 2850);
FORCEPROP 1 LAST TOLERANCE 10%
J 0
(1500 2800);
DISPLAY 0.617021 (1500 2800);
PAINT SKYBLUE (1500 2800);
FORCEPROP 1 LAST MATERIAL EMPTY
J 0
(1500 2750);
DISPLAY 0.617021 (1500 2750);
PAINT RED (1500 2750);
FORCEPROP 1 LAST PACK_TYPE C0402
J 0
(1500 2700);
DISPLAY 0.617021 (1500 2700);
PAINT SKYBLUE (1500 2700);
FORCEPROP 1 LAST LOCATION PC552
J 0
(1500 2950);
DISPLAY 0.617021 (1500 2950);
PAINT AQUA (1500 2950);
FORCEPROP 1 LASTPIN (1450 2925) $PN 1
J 0
(1460 2905);
DISPLAY 0.617021 (1460 2905);
PAINT MONO (1460 2905);
FORCEPROP 1 LASTPIN (1450 2725) $PN 2
J 0
(1460 2705);
DISPLAY 0.617021 (1460 2705);
PAINT MONO (1460 2705);
FORCEPROP 2 LAST CDS_LIB pure_quanta
J 0
(1450 2825);
DISPLAY INVISIBLE (1450 2825);
FORCEPROP 1 LAST PATH I120
J 0
(1500 2975);
DISPLAY 0.978723 (1500 2975);
PAINT WHITE (1500 2975);
DISPLAY INVISIBLE (1500 2975);
FORCEPROP 1 LAST LOCATION PC552
J 0
(1500 3000);
DISPLAY 1.021277 (1500 3000);
PAINT AQUA (1500 3000);
DISPLAY INVISIBLE (1500 3000);
FORCEPROP 0 LAST $SEC 1
J 0
(1500 3000);
DISPLAY 0.680851 (1500 3000);
PAINT MONO (1500 3000);
DISPLAY INVISIBLE (1500 3000);
FORCEPROP 0 LAST CDS_SEC 1
J 0
(1500 3000);
DISPLAY 1.021277 (1500 3000);
DISPLAY INVISIBLE (1500 3000);
FORCEADD Q_CAP..1
(1850 2350);
FORCEPROP 1 LAST PART_NUMBER CH5103KEB01
J 0
(1900 2175);
DISPLAY 0.617021 (1900 2175);
PAINT BLUE (1900 2175);
DISPLAY INVISIBLE (1900 2175);
FORCEPROP 1 LAST MATERIAL X6S
J 0
(1900 2275);
DISPLAY 0.617021 (1900 2275);
PAINT SKYBLUE (1900 2275);
FORCEPROP 1 LAST PACK_TYPE C0402
J 0
(1900 2225);
DISPLAY 0.617021 (1900 2225);
PAINT SKYBLUE (1900 2225);
FORCEPROP 1 LAST VALUE 1UF
J 0
(1900 2425);
DISPLAY 0.617021 (1900 2425);
PAINT SKYBLUE (1900 2425);
FORCEPROP 1 LAST TOLERANCE 10%
J 0
(1900 2325);
DISPLAY 0.617021 (1900 2325);
PAINT SKYBLUE (1900 2325);
FORCEPROP 1 LAST VOLTAGE 16V
J 0
(1900 2375);
DISPLAY 0.617021 (1900 2375);
PAINT SKYBLUE (1900 2375);
FORCEPROP 1 LAST LOCATION PC1194
J 0
(1900 2475);
DISPLAY 0.617021 (1900 2475);
PAINT AQUA (1900 2475);
FORCEPROP 1 LASTPIN (1850 2450) $PN 1
J 0
(1860 2430);
DISPLAY 0.617021 (1860 2430);
FORCEPROP 1 LASTPIN (1850 2250) $PN 2
J 0
(1860 2230);
DISPLAY 0.617021 (1860 2230);
FORCEPROP 2 LAST CDS_LIB pure_quanta
J 0
(1850 2350);
PAINT MONO (1850 2350);
DISPLAY INVISIBLE (1850 2350);
FORCEPROP 1 LAST PATH I121
J 0
(1900 2500);
DISPLAY 0.978723 (1900 2500);
PAINT WHITE (1900 2500);
DISPLAY INVISIBLE (1900 2500);
FORCEPROP 2 LAST $SEC 1
J 0
(1900 2550);
DISPLAY 0.680851 (1900 2550);
PAINT MONO (1900 2550);
DISPLAY INVISIBLE (1900 2550);
FORCEPROP 2 LAST CDS_SEC 1
J 0
(1900 2550);
DISPLAY 1.021277 (1900 2550);
DISPLAY INVISIBLE (1900 2550);
FORCEADD Q_CAP..1
(1850 2825);
FORCEPROP 1 LAST PART_NUMBER CH5103KEB01
J 0
(1900 2650);
DISPLAY 0.617021 (1900 2650);
PAINT BLUE (1900 2650);
DISPLAY INVISIBLE (1900 2650);
FORCEPROP 1 LAST MATERIAL X6S
J 0
(1900 2750);
DISPLAY 0.617021 (1900 2750);
PAINT SKYBLUE (1900 2750);
FORCEPROP 1 LAST VOLTAGE 16V
J 0
(1900 2850);
DISPLAY 0.617021 (1900 2850);
PAINT SKYBLUE (1900 2850);
FORCEPROP 1 LAST VALUE 1UF
J 0
(1900 2900);
DISPLAY 0.617021 (1900 2900);
PAINT SKYBLUE (1900 2900);
FORCEPROP 1 LAST TOLERANCE 10%
J 0
(1900 2800);
DISPLAY 0.617021 (1900 2800);
PAINT SKYBLUE (1900 2800);
FORCEPROP 1 LAST PACK_TYPE C0402
J 0
(1900 2700);
DISPLAY 0.617021 (1900 2700);
PAINT SKYBLUE (1900 2700);
FORCEPROP 1 LAST LOCATION PC555
J 0
(1900 2950);
DISPLAY 0.617021 (1900 2950);
PAINT AQUA (1900 2950);
FORCEPROP 1 LASTPIN (1850 2925) $PN 1
J 0
(1860 2905);
DISPLAY 0.617021 (1860 2905);
PAINT MONO (1860 2905);
FORCEPROP 1 LASTPIN (1850 2725) $PN 2
J 0
(1860 2705);
DISPLAY 0.617021 (1860 2705);
PAINT MONO (1860 2705);
FORCEPROP 2 LAST CDS_LIB pure_quanta
J 0
(1850 2825);
DISPLAY INVISIBLE (1850 2825);
FORCEPROP 1 LAST PATH I122
J 0
(1900 2975);
DISPLAY 0.978723 (1900 2975);
PAINT WHITE (1900 2975);
DISPLAY INVISIBLE (1900 2975);
FORCEPROP 1 LAST LOCATION PC555
J 0
(1900 3000);
DISPLAY 1.021277 (1900 3000);
PAINT AQUA (1900 3000);
DISPLAY INVISIBLE (1900 3000);
FORCEPROP 0 LAST $SEC 1
J 0
(1900 3000);
DISPLAY 0.680851 (1900 3000);
PAINT MONO (1900 3000);
DISPLAY INVISIBLE (1900 3000);
FORCEPROP 0 LAST CDS_SEC 1
J 0
(1900 3000);
DISPLAY 1.021277 (1900 3000);
DISPLAY INVISIBLE (1900 3000);
FORCEADD UNIVERSAL_GND..1
R 3
(2300 2150);
FORCEPROP 3 LASTPIN (2250 2150) SIG_NAME GND\g
J 0
(2260 2160);
DISPLAY 0.659574 (2260 2160);
PAINT MONO (2260 2160);
DISPLAY INVISIBLE (2260 2160);
FORCEPROP 1 LAST HDL_POWER GND
R 1
J 1
(2375 2125);
DISPLAY 0.872340 (2375 2125);
PAINT GREEN (2375 2125);
DISPLAY INVISIBLE (2375 2125);
FORCEPROP 2 LAST CDS_LIB logical_power
J 0
(2300 2150);
PAINT MONO (2300 2150);
DISPLAY INVISIBLE (2300 2150);
FORCEPROP 1 LAST PATH I123
R 1
J 2
(2300 2075);
DISPLAY 0.872340 (2300 2075);
PAINT AQUA (2300 2075);
DISPLAY INVISIBLE (2300 2075);
FORCEADD OFFPAGE..2
(2275 2550);
FORCEPROP 2 LAST $XR6 290 
J 0
(2584 2514);
DISPLAY 0.638298 (2584 2514);
PAINT MONO (2584 2514);
FORCEPROP 2 LAST $XR5 289 
J 0
(2464 2514);
DISPLAY 0.638298 (2464 2514);
PAINT MONO (2464 2514);
FORCEPROP 2 LAST $XR4 288 
J 0
(2944 2550);
DISPLAY 0.638298 (2944 2550);
PAINT MONO (2944 2550);
FORCEPROP 2 LAST $XR3 287 
J 0
(2824 2550);
DISPLAY 0.638298 (2824 2550);
PAINT MONO (2824 2550);
FORCEPROP 2 LAST $XR2 286 
J 0
(2704 2550);
DISPLAY 0.638298 (2704 2550);
PAINT MONO (2704 2550);
FORCEPROP 2 LAST $XR1 285 
J 0
(2584 2550);
DISPLAY 0.638298 (2584 2550);
PAINT MONO (2584 2550);
FORCEPROP 2 LAST $XR0 284 
J 0
(2464 2550);
DISPLAY 0.638298 (2464 2550);
PAINT MONO (2464 2550);
FORCEPROP 1 LAST COMMENT_BODY TRUE
J 0
(2230 2455);
DISPLAY 0.872340 (2230 2455);
PAINT GREEN (2230 2455);
DISPLAY INVISIBLE (2230 2455);
FORCEPROP 1 LAST OFFPAGE TRUE
J 0
(2600 2425);
DISPLAY 0.872340 (2600 2425);
PAINT GREEN (2600 2425);
DISPLAY INVISIBLE (2600 2425);
FORCEPROP 2 LAST CDS_LIB standard
J 0
(2275 2550);
DISPLAY INVISIBLE (2275 2550);
FORCEPROP 2 LAST PATH I124
J 0
(2825 2600);
DISPLAY 1.021277 (2825 2600);
DISPLAY INVISIBLE (2825 2600);
FORCEADD UNIVERSAL_GND..1
R 3
(2300 2625);
FORCEPROP 3 LASTPIN (2250 2625) SIG_NAME GND\g
J 0
(2260 2635);
DISPLAY 0.659574 (2260 2635);
PAINT MONO (2260 2635);
DISPLAY INVISIBLE (2260 2635);
FORCEPROP 1 LAST HDL_POWER GND
R 1
J 1
(2375 2600);
DISPLAY 0.872340 (2375 2600);
PAINT GREEN (2375 2600);
DISPLAY INVISIBLE (2375 2600);
FORCEPROP 2 LAST CDS_LIB logical_power
J 0
(2300 2625);
PAINT MONO (2300 2625);
DISPLAY INVISIBLE (2300 2625);
FORCEPROP 1 LAST PATH I125
R 1
J 2
(2300 2550);
DISPLAY 0.872340 (2300 2550);
PAINT AQUA (2300 2550);
DISPLAY INVISIBLE (2300 2550);
FORCEADD Q_RES..1
(2175 3025);
FORCEPROP 1 LAST PART_NUMBER CS-1002FB04
J 0
(2325 2975);
DISPLAY 0.617021 (2325 2975);
PAINT BLUE (2325 2975);
DISPLAY INVISIBLE (2325 2975);
FORCEPROP 1 LAST TOLERANCE 1%
J 0
(2375 3025);
DISPLAY 0.617021 (2375 3025);
PAINT SKYBLUE (2375 3025);
FORCEPROP 1 LAST VALUE 1
J 2
(2350 3025);
DISPLAY 0.617021 (2350 3025);
PAINT SKYBLUE (2350 3025);
FORCEPROP 1 LAST WATTAGE 1/16W
J 2
(2625 2925);
DISPLAY 0.617021 (2625 2925);
PAINT SKYBLUE (2625 2925);
FORCEPROP 1 LAST PACK_TYPE 0402LF
J 0
(2325 2925);
DISPLAY 0.617021 (2325 2925);
PAINT SKYBLUE (2325 2925);
FORCEPROP 1 LAST MATERIAL CHIP
J 0
(2475 3025);
DISPLAY 0.617021 (2475 3025);
PAINT SKYBLUE (2475 3025);
FORCEPROP 1 LAST LOCATION PR323
J 0
(1950 3025);
DISPLAY 0.617021 (1950 3025);
PAINT AQUA (1950 3025);
FORCEPROP 1 LASTPIN (2075 3025) $PN 1
J 0
(2087 3037);
DISPLAY 0.617021 (2087 3037);
PAINT MONO (2087 3037);
FORCEPROP 1 LASTPIN (2275 3025) $PN 2
J 0
(2237 3037);
DISPLAY 0.617021 (2237 3037);
PAINT MONO (2237 3037);
FORCEPROP 2 LAST CDS_LIB pure_quanta
J 0
(2175 3025);
DISPLAY INVISIBLE (2175 3025);
FORCEPROP 1 LAST PATH I126
J 0
(2125 3175);
DISPLAY 0.978723 (2125 3175);
PAINT WHITE (2125 3175);
DISPLAY INVISIBLE (2125 3175);
FORCEPROP 1 LAST LOCATION PR323
J 0
(2125 3125);
DISPLAY 1.021277 (2125 3125);
PAINT AQUA (2125 3125);
DISPLAY INVISIBLE (2125 3125);
FORCEPROP 0 LAST $SEC 1
J 0
(2125 3125);
DISPLAY 0.680851 (2125 3125);
PAINT MONO (2125 3125);
DISPLAY INVISIBLE (2125 3125);
FORCEPROP 0 LAST CDS_SEC 1
J 0
(2125 3125);
DISPLAY 1.021277 (2125 3125);
DISPLAY INVISIBLE (2125 3125);
FORCEADD VCC15..1
(2650 3150);
FORCEPROP 3 LASTPIN (2650 3100) SIG_NAME P3V3_AUX\g
J 0
(2660 3110);
DISPLAY 0.659574 (2660 3110);
PAINT MONO (2660 3110);
DISPLAY INVISIBLE (2660 3110);
FORCEPROP 1 LAST HDL_POWER P3V3_AUX
J 1
(2650 3200);
DISPLAY 0.617021 (2650 3200);
PAINT GREEN (2650 3200);
FORCEPROP 2 LAST CDS_LIB logical_power
J 0
(2650 3150);
DISPLAY INVISIBLE (2650 3150);
FORCEPROP 1 LAST PATH I127
J 0
(2700 3175);
DISPLAY 0.872340 (2700 3175);
PAINT AQUA (2700 3175);
DISPLAY INVISIBLE (2700 3175);
FORCEADD Q_CAP..1
(1100 2825);
FORCEPROP 1 LAST PART_NUMBER CH4104K1B00
J 0
(1150 2750);
DISPLAY 0.638298 (1150 2750);
DISPLAY INVISIBLE (1150 2750);
FORCEPROP 1 LAST PACK_TYPE 0402
J 0
(1150 2700);
DISPLAY 0.638298 (1150 2700);
FORCEPROP 1 LAST MATERIAL EMPTY
J 0
(1150 2775);
DISPLAY 0.638298 (1150 2775);
PAINT RED (1150 2775);
FORCEPROP 1 LAST TOLERANCE 10%
J 0
(1150 2800);
DISPLAY 0.638298 (1150 2800);
FORCEPROP 1 LAST VOLTAGE 25V
J 0
(1150 2850);
DISPLAY 0.638298 (1150 2850);
FORCEPROP 1 LAST VALUE 0.1UF
J 0
(1150 2900);
DISPLAY 0.638298 (1150 2900);
FORCEPROP 1 LAST LOCATION PC2366
J 0
(1150 2925);
DISPLAY 0.978723 (1150 2925);
FORCEPROP 1 LASTPIN (1100 2925) $PN 1
J 0
(1110 2905);
DISPLAY 0.787234 (1110 2905);
PAINT MONO (1110 2905);
FORCEPROP 1 LASTPIN (1100 2725) $PN 2
J 0
(1110 2705);
DISPLAY 0.787234 (1110 2705);
PAINT MONO (1110 2705);
FORCEPROP 1 LAST PATH I128
J 0
(1150 2975);
DISPLAY 0.978723 (1150 2975);
PAINT WHITE (1150 2975);
DISPLAY INVISIBLE (1150 2975);
FORCEPROP 2 LAST CDS_LIB pure_quanta
J 0
(1100 2825);
DISPLAY INVISIBLE (1100 2825);
FORCEPROP 0 LAST $SEC 1
J 0
(1150 2975);
DISPLAY 0.680851 (1150 2975);
PAINT MONO (1150 2975);
DISPLAY INVISIBLE (1150 2975);
FORCEPROP 0 LAST CDS_SEC 1
J 0
(1150 2975);
DISPLAY 1.021277 (1150 2975);
DISPLAY INVISIBLE (1150 2975);
FORCEADD VCC15..1
(-2775 -1000);
FORCEPROP 3 LASTPIN (-2775 -1050) SIG_NAME P3V3_AUX\g
J 0
(-2765 -1040);
DISPLAY 0.659574 (-2765 -1040);
PAINT MONO (-2765 -1040);
DISPLAY INVISIBLE (-2765 -1040);
FORCEPROP 1 LAST HDL_POWER P3V3_AUX
J 1
(-2775 -950);
DISPLAY 0.617021 (-2775 -950);
PAINT GREEN (-2775 -950);
FORCEPROP 2 LAST CDS_LIB logical_power
J 0
(-2775 -1000);
DISPLAY INVISIBLE (-2775 -1000);
FORCEPROP 1 LAST PATH I13
J 0
(-2725 -975);
DISPLAY 0.872340 (-2725 -975);
PAINT AQUA (-2725 -975);
DISPLAY INVISIBLE (-2725 -975);
FORCEADD VCC15..1
(-2475 -1525);
FORCEPROP 3 LASTPIN (-2475 -1575) SIG_NAME P3V3_AUX\g
J 0
(-2465 -1565);
DISPLAY 0.659574 (-2465 -1565);
PAINT MONO (-2465 -1565);
DISPLAY INVISIBLE (-2465 -1565);
FORCEPROP 1 LAST HDL_POWER P3V3_AUX
J 1
(-2475 -1475);
DISPLAY 0.617021 (-2475 -1475);
PAINT GREEN (-2475 -1475);
FORCEPROP 2 LAST CDS_LIB logical_power
J 0
(-2475 -1525);
PAINT MONO (-2475 -1525);
DISPLAY INVISIBLE (-2475 -1525);
FORCEPROP 1 LAST PATH I14
J 0
(-2425 -1500);
DISPLAY 0.872340 (-2425 -1500);
PAINT AQUA (-2425 -1500);
DISPLAY INVISIBLE (-2425 -1500);
FORCEADD Q_RES..1
(-2000 -1625);
FORCEPROP 1 LAST PART_NUMBER CS21002FB06
J 0
(-1875 -1575);
DISPLAY 0.617021 (-1875 -1575);
PAINT BLUE (-1875 -1575);
DISPLAY INVISIBLE (-1875 -1575);
FORCEPROP 1 LAST WATTAGE 1/16W
J 2
(-1575 -1525);
DISPLAY 0.617021 (-1575 -1525);
PAINT SKYBLUE (-1575 -1525);
FORCEPROP 1 LAST MATERIAL CHIP
J 0
(-1875 -1525);
DISPLAY 0.617021 (-1875 -1525);
PAINT SKYBLUE (-1875 -1525);
FORCEPROP 1 LAST TOLERANCE 1%
J 0
(-1800 -1625);
DISPLAY 0.617021 (-1800 -1625);
PAINT SKYBLUE (-1800 -1625);
FORCEPROP 1 LAST PACK_TYPE 0402LF
J 0
(-1700 -1625);
DISPLAY 0.617021 (-1700 -1625);
PAINT SKYBLUE (-1700 -1625);
FORCEPROP 1 LAST VALUE 1K
J 2
(-1825 -1625);
DISPLAY 0.617021 (-1825 -1625);
PAINT SKYBLUE (-1825 -1625);
FORCEPROP 1 LAST LOCATION R2551
J 0
(-2225 -1625);
DISPLAY 0.617021 (-2225 -1625);
PAINT AQUA (-2225 -1625);
FORCEPROP 1 LASTPIN (-2100 -1625) $PN 1
J 0
(-2088 -1613);
DISPLAY 0.617021 (-2088 -1613);
PAINT MONO (-2088 -1613);
FORCEPROP 1 LASTPIN (-1900 -1625) $PN 2
J 0
(-1938 -1613);
DISPLAY 0.617021 (-1938 -1613);
PAINT MONO (-1938 -1613);
FORCEPROP 2 LAST CDS_LIB pure_quanta
J 0
(-2000 -1625);
DISPLAY INVISIBLE (-2000 -1625);
FORCEPROP 1 LAST PATH I15
J 0
(-2050 -1475);
DISPLAY 0.978723 (-2050 -1475);
PAINT WHITE (-2050 -1475);
DISPLAY INVISIBLE (-2050 -1475);
FORCEPROP 1 LAST LOCATION R2551
J 0
(-2050 -1525);
DISPLAY 1.021277 (-2050 -1525);
PAINT AQUA (-2050 -1525);
DISPLAY INVISIBLE (-2050 -1525);
FORCEPROP 0 LAST $SEC 1
J 0
(-2050 -1525);
DISPLAY 0.680851 (-2050 -1525);
PAINT MONO (-2050 -1525);
DISPLAY INVISIBLE (-2050 -1525);
FORCEPROP 0 LAST CDS_SEC 1
J 0
(-2050 -1525);
DISPLAY 1.021277 (-2050 -1525);
DISPLAY INVISIBLE (-2050 -1525);
FORCEADD Q_RES..1
(-2000 -1775);
FORCEPROP 1 LAST PART_NUMBER CS00002JB13
J 0
(-1875 -1725);
DISPLAY 0.617021 (-1875 -1725);
PAINT BLUE (-1875 -1725);
DISPLAY INVISIBLE (-1875 -1725);
FORCEPROP 1 LAST MATERIAL CHIP
J 0
(-1875 -1675);
DISPLAY 0.617021 (-1875 -1675);
PAINT SKYBLUE (-1875 -1675);
FORCEPROP 1 LAST PACK_TYPE 0402LF
J 0
(-1750 -1775);
DISPLAY 0.617021 (-1750 -1775);
PAINT SKYBLUE (-1750 -1775);
FORCEPROP 1 LAST TOLERANCE 5%
J 0
(-1825 -1775);
DISPLAY 0.617021 (-1825 -1775);
PAINT SKYBLUE (-1825 -1775);
FORCEPROP 1 LAST WATTAGE 1/16W
J 2
(-1575 -1675);
DISPLAY 0.617021 (-1575 -1675);
PAINT SKYBLUE (-1575 -1675);
FORCEPROP 1 LAST VALUE 0
J 2
(-1850 -1775);
DISPLAY 0.617021 (-1850 -1775);
PAINT SKYBLUE (-1850 -1775);
FORCEPROP 1 LAST LOCATION R2552
J 0
(-2225 -1775);
DISPLAY 0.617021 (-2225 -1775);
PAINT AQUA (-2225 -1775);
FORCEPROP 1 LASTPIN (-2100 -1775) $PN 1
J 0
(-2088 -1763);
DISPLAY 0.617021 (-2088 -1763);
PAINT MONO (-2088 -1763);
FORCEPROP 1 LASTPIN (-1900 -1775) $PN 2
J 0
(-1938 -1763);
DISPLAY 0.617021 (-1938 -1763);
PAINT MONO (-1938 -1763);
FORCEPROP 2 LAST CDS_LIB pure_quanta
J 0
(-2000 -1775);
DISPLAY INVISIBLE (-2000 -1775);
FORCEPROP 1 LAST PATH I16
J 0
(-2050 -1625);
DISPLAY 0.978723 (-2050 -1625);
PAINT WHITE (-2050 -1625);
DISPLAY INVISIBLE (-2050 -1625);
FORCEPROP 1 LAST LOCATION R2552
J 0
(-2050 -1675);
DISPLAY 1.021277 (-2050 -1675);
PAINT AQUA (-2050 -1675);
DISPLAY INVISIBLE (-2050 -1675);
FORCEPROP 0 LAST $SEC 1
J 0
(-2050 -1675);
DISPLAY 0.680851 (-2050 -1675);
PAINT MONO (-2050 -1675);
DISPLAY INVISIBLE (-2050 -1675);
FORCEPROP 0 LAST CDS_SEC 1
J 0
(-2050 -1675);
DISPLAY 1.021277 (-2050 -1675);
DISPLAY INVISIBLE (-2050 -1675);
FORCEADD Q_RES..1
(-2300 -975);
FORCEPROP 1 LAST PART_NUMBER CS21002FB06
J 0
(-2175 -925);
DISPLAY 0.617021 (-2175 -925);
PAINT BLUE (-2175 -925);
DISPLAY INVISIBLE (-2175 -925);
FORCEPROP 1 LAST VALUE 1K
J 2
(-2125 -975);
DISPLAY 0.617021 (-2125 -975);
PAINT SKYBLUE (-2125 -975);
FORCEPROP 1 LAST PACK_TYPE 0402LF
J 0
(-2025 -975);
DISPLAY 0.617021 (-2025 -975);
PAINT SKYBLUE (-2025 -975);
FORCEPROP 1 LAST MATERIAL CHIP
J 0
(-2175 -875);
DISPLAY 0.617021 (-2175 -875);
PAINT SKYBLUE (-2175 -875);
FORCEPROP 1 LAST TOLERANCE 1%
J 0
(-2100 -975);
DISPLAY 0.617021 (-2100 -975);
PAINT SKYBLUE (-2100 -975);
FORCEPROP 1 LAST WATTAGE 1/16W
J 2
(-1900 -875);
DISPLAY 0.617021 (-1900 -875);
PAINT SKYBLUE (-1900 -875);
FORCEPROP 1 LAST LOCATION R2524
J 0
(-2550 -975);
DISPLAY 0.617021 (-2550 -975);
PAINT AQUA (-2550 -975);
FORCEPROP 1 LASTPIN (-2400 -975) $PN 1
J 0
(-2388 -963);
DISPLAY 0.617021 (-2388 -963);
FORCEPROP 1 LASTPIN (-2200 -975) $PN 2
J 0
(-2238 -963);
DISPLAY 0.617021 (-2238 -963);
FORCEPROP 2 LAST CDS_LIB pure_quanta
J 0
(-2300 -975);
PAINT MONO (-2300 -975);
DISPLAY INVISIBLE (-2300 -975);
FORCEPROP 1 LAST PATH I17
J 0
(-2350 -825);
DISPLAY 0.978723 (-2350 -825);
PAINT WHITE (-2350 -825);
DISPLAY INVISIBLE (-2350 -825);
FORCEPROP 2 LAST $SEC 1
J 0
(-2350 -775);
DISPLAY 0.680851 (-2350 -775);
PAINT MONO (-2350 -775);
DISPLAY INVISIBLE (-2350 -775);
FORCEPROP 2 LAST CDS_SEC 1
J 0
(-2350 -775);
DISPLAY 1.021277 (-2350 -775);
DISPLAY INVISIBLE (-2350 -775);
FORCEADD Q_RES..1
(-2300 -1075);
FORCEPROP 1 LAST PART_NUMBER CS21002FB06
J 0
(-2175 -1025);
DISPLAY 0.510638 (-2175 -1025);
PAINT BLUE (-2175 -1025);
DISPLAY INVISIBLE (-2175 -1025);
FORCEPROP 1 LAST VALUE 1K
J 2
(-2125 -1075);
DISPLAY 0.617021 (-2125 -1075);
PAINT SKYBLUE (-2125 -1075);
FORCEPROP 1 LAST TOLERANCE 1%
J 0
(-2100 -1075);
DISPLAY 0.617021 (-2100 -1075);
PAINT SKYBLUE (-2100 -1075);
FORCEPROP 1 LAST PACK_TYPE 0402LF
J 0
(-2025 -1075);
DISPLAY 0.617021 (-2025 -1075);
PAINT SKYBLUE (-2025 -1075);
FORCEPROP 1 LAST LOCATION R2525
J 0
(-2550 -1075);
DISPLAY 0.617021 (-2550 -1075);
PAINT AQUA (-2550 -1075);
FORCEPROP 1 LASTPIN (-2400 -1075) $PN 1
J 0
(-2388 -1063);
DISPLAY 0.617021 (-2388 -1063);
FORCEPROP 1 LASTPIN (-2200 -1075) $PN 2
J 0
(-2238 -1063);
DISPLAY 0.617021 (-2238 -1063);
FORCEPROP 1 LAST MATERIAL CHIP
J 0
(-2175 -975);
DISPLAY 0.510638 (-2175 -975);
PAINT SKYBLUE (-2175 -975);
DISPLAY INVISIBLE (-2175 -975);
FORCEPROP 1 LAST WATTAGE 1/16W
J 2
(-1925 -975);
DISPLAY 0.510638 (-1925 -975);
PAINT SKYBLUE (-1925 -975);
DISPLAY INVISIBLE (-1925 -975);
FORCEPROP 2 LAST CDS_LIB pure_quanta
J 0
(-2300 -1075);
PAINT MONO (-2300 -1075);
DISPLAY INVISIBLE (-2300 -1075);
FORCEPROP 1 LAST PATH I18
J 0
(-2350 -925);
DISPLAY 0.978723 (-2350 -925);
PAINT WHITE (-2350 -925);
DISPLAY INVISIBLE (-2350 -925);
FORCEPROP 2 LAST $SEC 1
J 0
(-2350 -875);
DISPLAY 0.680851 (-2350 -875);
PAINT MONO (-2350 -875);
DISPLAY INVISIBLE (-2350 -875);
FORCEPROP 2 LAST CDS_SEC 1
J 0
(-2350 -875);
DISPLAY 1.021277 (-2350 -875);
DISPLAY INVISIBLE (-2350 -875);
FORCEADD Q_RES..1
(-2000 -1375);
FORCEPROP 1 LAST PART_NUMBER CS00002JB13
J 0
(-1875 -1325);
DISPLAY 0.617021 (-1875 -1325);
PAINT BLUE (-1875 -1325);
DISPLAY INVISIBLE (-1875 -1325);
FORCEPROP 1 LAST MATERIAL CHIP
J 0
(-1875 -1275);
DISPLAY 0.617021 (-1875 -1275);
PAINT SKYBLUE (-1875 -1275);
FORCEPROP 1 LAST PACK_TYPE 0402LF
J 0
(-1750 -1375);
DISPLAY 0.617021 (-1750 -1375);
PAINT SKYBLUE (-1750 -1375);
FORCEPROP 1 LAST TOLERANCE 5%
J 0
(-1825 -1375);
DISPLAY 0.617021 (-1825 -1375);
PAINT SKYBLUE (-1825 -1375);
FORCEPROP 1 LAST VALUE 0
J 2
(-1850 -1375);
DISPLAY 0.617021 (-1850 -1375);
PAINT SKYBLUE (-1850 -1375);
FORCEPROP 1 LAST WATTAGE 1/16W
J 2
(-1575 -1275);
DISPLAY 0.617021 (-1575 -1275);
PAINT SKYBLUE (-1575 -1275);
FORCEPROP 1 LAST LOCATION R2550
J 0
(-2225 -1375);
DISPLAY 0.617021 (-2225 -1375);
PAINT AQUA (-2225 -1375);
FORCEPROP 1 LASTPIN (-2100 -1375) $PN 1
J 0
(-2088 -1363);
DISPLAY 0.617021 (-2088 -1363);
PAINT MONO (-2088 -1363);
FORCEPROP 1 LASTPIN (-1900 -1375) $PN 2
J 0
(-1938 -1363);
DISPLAY 0.617021 (-1938 -1363);
PAINT MONO (-1938 -1363);
FORCEPROP 2 LAST CDS_LIB pure_quanta
J 0
(-2000 -1375);
DISPLAY INVISIBLE (-2000 -1375);
FORCEPROP 1 LAST PATH I19
J 0
(-2050 -1225);
DISPLAY 0.978723 (-2050 -1225);
PAINT WHITE (-2050 -1225);
DISPLAY INVISIBLE (-2050 -1225);
FORCEPROP 1 LAST LOCATION R2550
J 0
(-2050 -1275);
DISPLAY 1.021277 (-2050 -1275);
PAINT AQUA (-2050 -1275);
DISPLAY INVISIBLE (-2050 -1275);
FORCEPROP 0 LAST $SEC 1
J 0
(-2050 -1275);
DISPLAY 0.680851 (-2050 -1275);
PAINT MONO (-2050 -1275);
DISPLAY INVISIBLE (-2050 -1275);
FORCEPROP 0 LAST CDS_SEC 1
J 0
(-2050 -1275);
DISPLAY 1.021277 (-2050 -1275);
DISPLAY INVISIBLE (-2050 -1275);
FORCEADD OFFPAGE..1
(-4050 -450);
FORCEPROP 2 LAST $XR0 47 
J 0
(-4361 -450);
DISPLAY 0.638298 (-4361 -450);
PAINT MONO (-4361 -450);
FORCEPROP 1 LAST COMMENT_BODY TRUE
J 0
(-3925 -550);
DISPLAY 0.872340 (-3925 -550);
PAINT GREEN (-3925 -550);
DISPLAY INVISIBLE (-3925 -550);
FORCEPROP 1 LAST OFFPAGE TRUE
J 0
(-3725 -575);
DISPLAY 0.872340 (-3725 -575);
PAINT GREEN (-3725 -575);
DISPLAY INVISIBLE (-3725 -575);
FORCEPROP 2 LAST CDS_LIB standard
J 0
(-4050 -450);
DISPLAY INVISIBLE (-4050 -450);
FORCEPROP 2 LAST PATH I2
J 0
(-4350 -400);
DISPLAY 1.021277 (-4350 -400);
DISPLAY INVISIBLE (-4350 -400);
FORCEADD OFFPAGE..5
(-2775 -825);
FORCEPROP 2 LAST $XR0 214 
J 0
(-3030 -825);
DISPLAY 0.638298 (-3030 -825);
PAINT MONO (-3030 -825);
FORCEPROP 1 LAST COMMENT_BODY TRUE
J 0
(-2675 -900);
DISPLAY 0.872340 (-2675 -900);
PAINT GREEN (-2675 -900);
DISPLAY INVISIBLE (-2675 -900);
FORCEPROP 1 LAST OFFPAGE TRUE
J 0
(-2450 -950);
DISPLAY 0.872340 (-2450 -950);
PAINT GREEN (-2450 -950);
DISPLAY INVISIBLE (-2450 -950);
FORCEPROP 2 LAST CDS_LIB standard
J 0
(-2775 -825);
DISPLAY INVISIBLE (-2775 -825);
FORCEPROP 2 LAST PATH I20
J 0
(-3025 -775);
DISPLAY 1.021277 (-3025 -775);
DISPLAY INVISIBLE (-3025 -775);
FORCEADD UNIVERSAL_GND..1
(-2600 -675);
FORCEPROP 3 LASTPIN (-2600 -625) SIG_NAME GND\g
J 0
(-2590 -615);
DISPLAY 0.659574 (-2590 -615);
PAINT MONO (-2590 -615);
DISPLAY INVISIBLE (-2590 -615);
FORCEPROP 1 LAST HDL_POWER GND
J 1
(-2575 -750);
DISPLAY 0.872340 (-2575 -750);
PAINT GREEN (-2575 -750);
DISPLAY INVISIBLE (-2575 -750);
FORCEPROP 2 LAST CDS_LIB logical_power
J 0
(-2600 -675);
PAINT MONO (-2600 -675);
DISPLAY INVISIBLE (-2600 -675);
FORCEPROP 1 LAST PATH I21
J 0
(-2525 -675);
DISPLAY 0.872340 (-2525 -675);
PAINT AQUA (-2525 -675);
DISPLAY INVISIBLE (-2525 -675);
FORCEADD Q_SHORT..1
(-2875 -75);
FORCEPROP 1 LAST PART_NUMBER SHORT6
J 0
(-2850 -315);
DISPLAY 0.617021 (-2850 -315);
PAINT BLUE (-2850 -315);
DISPLAY INVISIBLE (-2850 -315);
FORCEPROP 1 LAST MATERIAL EMPTY
J 0
(-2850 -265);
DISPLAY 0.617021 (-2850 -265);
PAINT RED (-2850 -265);
FORCEPROP 2 LAST PACK_TYPE SM
J 0
(-2850 -225);
DISPLAY 0.617021 (-2850 -225);
PAINT SKYBLUE (-2850 -225);
FORCEPROP 1 LAST LOCATION PJ49
J 0
(-2975 -220);
DISPLAY 0.617021 (-2975 -220);
PAINT AQUA (-2975 -220);
FORCEPROP 0 LASTPIN (-3000 -75) $PN 1
J 2
(-3010 -65);
DISPLAY 0.617021 (-3010 -65);
PAINT MONO (-3010 -65);
FORCEPROP 0 LASTPIN (-2750 -75) $PN 2
J 0
(-2740 -65);
DISPLAY 0.617021 (-2740 -65);
PAINT MONO (-2740 -65);
FORCEPROP 1 LAST NEEDS_NO_SIZE TRUE
J 0
(-2875 -75);
DISPLAY 0.468085 (-2875 -75);
PAINT GREEN (-2875 -75);
DISPLAY INVISIBLE (-2875 -75);
FORCEPROP 2 LAST CDS_LIB pure_quanta
J 0
(-2875 -75);
DISPLAY INVISIBLE (-2875 -75);
FORCEPROP 1 LAST PATH I22
J 0
(-2950 130);
DISPLAY 0.723404 (-2950 130);
PAINT GREEN (-2950 130);
DISPLAY INVISIBLE (-2950 130);
FORCEPROP 1 LAST LOCATION PJ49
J 0
(-2950 175);
DISPLAY 1.021277 (-2950 175);
PAINT AQUA (-2950 175);
DISPLAY INVISIBLE (-2950 175);
FORCEPROP 0 LAST $SEC 1
J 0
(-2950 175);
DISPLAY 0.680851 (-2950 175);
PAINT MONO (-2950 175);
DISPLAY INVISIBLE (-2950 175);
FORCEPROP 0 LAST CDS_SEC 1
J 0
(-2950 175);
DISPLAY 1.021277 (-2950 175);
DISPLAY INVISIBLE (-2950 175);
FORCEADD Q_RES..1
(-2800 75);
FORCEPROP 1 LAST PART_NUMBER CS11002FB07
J 0
(-2675 125);
DISPLAY 0.617021 (-2675 125);
PAINT BLUE (-2675 125);
DISPLAY INVISIBLE (-2675 125);
FORCEPROP 1 LAST MATERIAL CHIP
J 0
(-2675 175);
DISPLAY 0.617021 (-2675 175);
PAINT SKYBLUE (-2675 175);
FORCEPROP 1 LAST TOLERANCE 1%
J 0
(-2575 75);
DISPLAY 0.617021 (-2575 75);
PAINT SKYBLUE (-2575 75);
FORCEPROP 1 LAST VALUE 100
J 2
(-2600 75);
DISPLAY 0.617021 (-2600 75);
PAINT SKYBLUE (-2600 75);
FORCEPROP 1 LAST WATTAGE 1/16W
J 2
(-2375 175);
DISPLAY 0.617021 (-2375 175);
PAINT SKYBLUE (-2375 175);
FORCEPROP 1 LAST PACK_TYPE 0402LF
J 0
(-2500 75);
DISPLAY 0.617021 (-2500 75);
PAINT SKYBLUE (-2500 75);
FORCEPROP 1 LAST LOCATION PR561
J 0
(-3000 75);
DISPLAY 0.617021 (-3000 75);
PAINT AQUA (-3000 75);
FORCEPROP 1 LASTPIN (-2900 75) $PN 1
J 0
(-2888 87);
DISPLAY 0.617021 (-2888 87);
FORCEPROP 1 LASTPIN (-2700 75) $PN 2
J 0
(-2738 87);
DISPLAY 0.617021 (-2738 87);
FORCEPROP 2 LAST CDS_LIB pure_quanta
J 0
(-2800 75);
PAINT MONO (-2800 75);
DISPLAY INVISIBLE (-2800 75);
FORCEPROP 1 LAST PATH I23
J 0
(-2850 225);
DISPLAY 0.978723 (-2850 225);
PAINT WHITE (-2850 225);
DISPLAY INVISIBLE (-2850 225);
FORCEPROP 2 LAST $SEC 1
J 0
(-2850 275);
DISPLAY 0.680851 (-2850 275);
PAINT MONO (-2850 275);
DISPLAY INVISIBLE (-2850 275);
FORCEPROP 2 LAST CDS_SEC 1
J 0
(-2850 275);
DISPLAY 1.021277 (-2850 275);
DISPLAY INVISIBLE (-2850 275);
FORCEADD VCC15..1
(-2450 -575);
FORCEPROP 3 LASTPIN (-2450 -625) SIG_NAME P3V3_AUX\g
J 0
(-2440 -615);
DISPLAY 0.659574 (-2440 -615);
PAINT MONO (-2440 -615);
DISPLAY INVISIBLE (-2440 -615);
FORCEPROP 1 LAST HDL_POWER P3V3_AUX
J 1
(-2450 -525);
DISPLAY 0.617021 (-2450 -525);
PAINT GREEN (-2450 -525);
FORCEPROP 2 LAST CDS_LIB logical_power
J 0
(-2450 -575);
DISPLAY INVISIBLE (-2450 -575);
FORCEPROP 1 LAST PATH I24
J 0
(-2400 -550);
DISPLAY 0.872340 (-2400 -550);
PAINT AQUA (-2400 -550);
DISPLAY INVISIBLE (-2400 -550);
FORCEADD Q_RES..1
(-2300 -675);
FORCEPROP 1 LAST PART_NUMBER CS21002FB06
J 0
(-2175 -625);
DISPLAY 0.510638 (-2175 -625);
PAINT BLUE (-2175 -625);
DISPLAY INVISIBLE (-2175 -625);
FORCEPROP 1 LAST VALUE 1K
J 2
(-2125 -675);
DISPLAY 0.489362 (-2125 -675);
PAINT SKYBLUE (-2125 -675);
FORCEPROP 1 LAST TOLERANCE 1%
J 0
(-2100 -675);
DISPLAY 0.489362 (-2100 -675);
PAINT SKYBLUE (-2100 -675);
FORCEPROP 1 LAST PACK_TYPE 0402LF
J 0
(-2025 -675);
DISPLAY 0.489362 (-2025 -675);
PAINT SKYBLUE (-2025 -675);
FORCEPROP 1 LAST LOCATION R2522
J 0
(-2400 -625);
DISPLAY 0.617021 (-2400 -625);
PAINT AQUA (-2400 -625);
FORCEPROP 2 LAST CDS_LIB pure_quanta
J 0
(-2300 -675);
DISPLAY INVISIBLE (-2300 -675);
FORCEPROP 1 LAST WATTAGE 1/16W
J 2
(-1925 -575);
DISPLAY 0.510638 (-1925 -575);
PAINT SKYBLUE (-1925 -575);
DISPLAY INVISIBLE (-1925 -575);
FORCEPROP 1 LAST MATERIAL CHIP
J 0
(-2175 -575);
DISPLAY 0.510638 (-2175 -575);
PAINT SKYBLUE (-2175 -575);
DISPLAY INVISIBLE (-2175 -575);
FORCEPROP 1 LAST PATH I25
J 0
(-2350 -525);
DISPLAY 0.978723 (-2350 -525);
PAINT WHITE (-2350 -525);
DISPLAY INVISIBLE (-2350 -525);
FORCEPROP 0 LAST $SEC 1
J 0
(-2025 -625);
DISPLAY INVISIBLE (-2025 -625);
FORCEPROP 0 LAST CDS_SEC 1
J 0
(-2025 -625);
DISPLAY INVISIBLE (-2025 -625);
FORCEPROP 1 LASTPIN (-2400 -675) $PN 1
J 0
(-2388 -663);
DISPLAY 0.787234 (-2388 -663);
PAINT MONO (-2388 -663);
DISPLAY INVISIBLE (-2388 -663);
FORCEPROP 1 LASTPIN (-2200 -675) $PN 2
J 0
(-2238 -663);
DISPLAY 0.787234 (-2238 -663);
PAINT MONO (-2238 -663);
DISPLAY INVISIBLE (-2238 -663);
FORCEADD UNIVERSAL_GND..1
(-1475 -2925);
FORCEPROP 3 LASTPIN (-1475 -2875) SIG_NAME GND\g
J 0
(-1465 -2865);
DISPLAY 0.659574 (-1465 -2865);
PAINT MONO (-1465 -2865);
DISPLAY INVISIBLE (-1465 -2865);
FORCEPROP 1 LAST HDL_POWER GND
J 1
(-1450 -3000);
DISPLAY 0.872340 (-1450 -3000);
PAINT GREEN (-1450 -3000);
DISPLAY INVISIBLE (-1450 -3000);
FORCEPROP 2 LAST CDS_LIB logical_power
J 0
(-1475 -2925);
PAINT MONO (-1475 -2925);
DISPLAY INVISIBLE (-1475 -2925);
FORCEPROP 1 LAST PATH I26
J 0
(-1400 -2925);
DISPLAY 0.872340 (-1400 -2925);
PAINT AQUA (-1400 -2925);
DISPLAY INVISIBLE (-1400 -2925);
FORCEADD Q_RES..2
(-1800 -2625);
FORCEPROP 1 LAST PART_NUMBER CS00002JB13
J 0
(-1760 -2750);
DISPLAY 0.617021 (-1760 -2750);
PAINT BLUE (-1760 -2750);
DISPLAY INVISIBLE (-1760 -2750);
FORCEPROP 1 LAST WATTAGE 1/16W
J 0
(-1760 -2650);
DISPLAY 0.617021 (-1760 -2650);
PAINT SKYBLUE (-1760 -2650);
FORCEPROP 1 LAST MATERIAL CHIP
J 0
(-1760 -2700);
DISPLAY 0.617021 (-1760 -2700);
PAINT SKYBLUE (-1760 -2700);
FORCEPROP 1 LAST TOLERANCE 5%
J 0
(-1755 -2600);
DISPLAY 0.617021 (-1755 -2600);
PAINT SKYBLUE (-1755 -2600);
FORCEPROP 1 LAST PACK_TYPE 0402LF
J 0
(-1760 -2800);
DISPLAY 0.617021 (-1760 -2800);
PAINT SKYBLUE (-1760 -2800);
FORCEPROP 1 LAST VALUE 0
J 0
(-1755 -2550);
DISPLAY 0.617021 (-1755 -2550);
PAINT SKYBLUE (-1755 -2550);
FORCEPROP 1 LAST LOCATION PR305
J 0
(-1755 -2500);
DISPLAY 0.617021 (-1755 -2500);
PAINT AQUA (-1755 -2500);
FORCEPROP 1 LASTPIN (-1800 -2525) $PN 1
J 0
(-1795 -2563);
DISPLAY 0.617021 (-1795 -2563);
PAINT MONO (-1795 -2563);
FORCEPROP 1 LASTPIN (-1800 -2725) $PN 2
J 0
(-1795 -2715);
DISPLAY 0.617021 (-1795 -2715);
PAINT MONO (-1795 -2715);
FORCEPROP 2 LAST CDS_LIB pure_quanta
J 0
(-1800 -2625);
DISPLAY INVISIBLE (-1800 -2625);
FORCEPROP 1 LAST PATH I27
J 0
(-1750 -2450);
DISPLAY 0.978723 (-1750 -2450);
PAINT WHITE (-1750 -2450);
DISPLAY INVISIBLE (-1750 -2450);
FORCEPROP 1 LAST LOCATION PR305
J 0
(-1750 -2450);
DISPLAY 1.021277 (-1750 -2450);
PAINT AQUA (-1750 -2450);
DISPLAY INVISIBLE (-1750 -2450);
FORCEPROP 0 LAST $SEC 1
J 0
(-1750 -2450);
DISPLAY 0.680851 (-1750 -2450);
PAINT MONO (-1750 -2450);
DISPLAY INVISIBLE (-1750 -2450);
FORCEPROP 0 LAST CDS_SEC 1
J 0
(-1750 -2450);
DISPLAY 1.021277 (-1750 -2450);
DISPLAY INVISIBLE (-1750 -2450);
FORCEADD Q_CAP..1
(-1475 -2625);
FORCEPROP 1 LAST PART_NUMBER CH4104K1B00
J 0
(-1425 -2800);
DISPLAY 0.617021 (-1425 -2800);
PAINT BLUE (-1425 -2800);
DISPLAY INVISIBLE (-1425 -2800);
FORCEPROP 1 LAST PACK_TYPE 0402
J 0
(-1425 -2750);
DISPLAY 0.617021 (-1425 -2750);
PAINT SKYBLUE (-1425 -2750);
FORCEPROP 1 LAST MATERIAL EMPTY
J 0
(-1425 -2700);
DISPLAY 0.617021 (-1425 -2700);
PAINT RED (-1425 -2700);
FORCEPROP 1 LAST TOLERANCE 10%
J 0
(-1425 -2650);
DISPLAY 0.617021 (-1425 -2650);
PAINT SKYBLUE (-1425 -2650);
FORCEPROP 1 LAST VALUE 0.1UF
J 0
(-1425 -2550);
DISPLAY 0.617021 (-1425 -2550);
PAINT SKYBLUE (-1425 -2550);
FORCEPROP 1 LAST VOLTAGE 25V
J 0
(-1425 -2600);
DISPLAY 0.617021 (-1425 -2600);
PAINT SKYBLUE (-1425 -2600);
FORCEPROP 1 LAST LOCATION PC547
J 0
(-1425 -2500);
DISPLAY 0.617021 (-1425 -2500);
PAINT AQUA (-1425 -2500);
FORCEPROP 1 LASTPIN (-1475 -2525) $PN 1
J 0
(-1465 -2545);
DISPLAY 0.617021 (-1465 -2545);
PAINT MONO (-1465 -2545);
FORCEPROP 1 LASTPIN (-1475 -2725) $PN 2
J 0
(-1465 -2745);
DISPLAY 0.617021 (-1465 -2745);
PAINT MONO (-1465 -2745);
FORCEPROP 2 LAST CDS_LIB pure_quanta
J 0
(-1475 -2625);
DISPLAY INVISIBLE (-1475 -2625);
FORCEPROP 1 LAST PATH I28
J 0
(-1425 -2475);
DISPLAY 0.978723 (-1425 -2475);
PAINT WHITE (-1425 -2475);
DISPLAY INVISIBLE (-1425 -2475);
FORCEPROP 1 LAST LOCATION PC547
J 0
(-1425 -2450);
DISPLAY 1.021277 (-1425 -2450);
PAINT AQUA (-1425 -2450);
DISPLAY INVISIBLE (-1425 -2450);
FORCEPROP 0 LAST $SEC 1
J 0
(-1425 -2450);
DISPLAY 0.680851 (-1425 -2450);
PAINT MONO (-1425 -2450);
DISPLAY INVISIBLE (-1425 -2450);
FORCEPROP 0 LAST CDS_SEC 1
J 0
(-1425 -2450);
DISPLAY 1.021277 (-1425 -2450);
DISPLAY INVISIBLE (-1425 -2450);
FORCEADD Q_RES..2
(-1050 -2625);
FORCEPROP 1 LAST PART_NUMBER CS21002FB06
J 0
(-1010 -2750);
DISPLAY 0.617021 (-1010 -2750);
PAINT BLUE (-1010 -2750);
DISPLAY INVISIBLE (-1010 -2750);
FORCEPROP 1 LAST WATTAGE 1/16W
J 0
(-1010 -2650);
DISPLAY 0.617021 (-1010 -2650);
PAINT SKYBLUE (-1010 -2650);
FORCEPROP 1 LAST MATERIAL EMPTY
J 0
(-1010 -2700);
DISPLAY 0.617021 (-1010 -2700);
PAINT RED (-1010 -2700);
FORCEPROP 1 LAST TOLERANCE 1%
J 0
(-1005 -2600);
DISPLAY 0.617021 (-1005 -2600);
PAINT SKYBLUE (-1005 -2600);
FORCEPROP 1 LAST VALUE 1K
J 0
(-1005 -2550);
DISPLAY 0.617021 (-1005 -2550);
PAINT SKYBLUE (-1005 -2550);
FORCEPROP 1 LAST PACK_TYPE 0402LF
J 0
(-1010 -2800);
DISPLAY 0.617021 (-1010 -2800);
PAINT SKYBLUE (-1010 -2800);
FORCEPROP 1 LAST LOCATION PR313
J 0
(-1005 -2500);
DISPLAY 0.617021 (-1005 -2500);
PAINT AQUA (-1005 -2500);
FORCEPROP 1 LASTPIN (-1050 -2525) $PN 1
J 0
(-1045 -2563);
DISPLAY 0.617021 (-1045 -2563);
PAINT MONO (-1045 -2563);
FORCEPROP 1 LASTPIN (-1050 -2725) $PN 2
J 0
(-1045 -2715);
DISPLAY 0.617021 (-1045 -2715);
PAINT MONO (-1045 -2715);
FORCEPROP 2 LAST CDS_LIB pure_quanta
J 0
(-1050 -2625);
DISPLAY INVISIBLE (-1050 -2625);
FORCEPROP 1 LAST PATH I29
J 0
(-1000 -2450);
DISPLAY 0.978723 (-1000 -2450);
PAINT WHITE (-1000 -2450);
DISPLAY INVISIBLE (-1000 -2450);
FORCEPROP 1 LAST LOCATION PR313
J 0
(-1000 -2450);
DISPLAY 1.021277 (-1000 -2450);
PAINT AQUA (-1000 -2450);
DISPLAY INVISIBLE (-1000 -2450);
FORCEPROP 0 LAST $SEC 1
J 0
(-1000 -2450);
DISPLAY 0.680851 (-1000 -2450);
PAINT MONO (-1000 -2450);
DISPLAY INVISIBLE (-1000 -2450);
FORCEPROP 0 LAST CDS_SEC 1
J 0
(-1000 -2450);
DISPLAY 1.021277 (-1000 -2450);
DISPLAY INVISIBLE (-1000 -2450);
FORCEADD OFFPAGE..1
(-4050 -75);
FORCEPROP 2 LAST $XR0 47 
J 0
(-4361 -75);
DISPLAY 0.638298 (-4361 -75);
PAINT MONO (-4361 -75);
FORCEPROP 1 LAST COMMENT_BODY TRUE
J 0
(-3925 -175);
DISPLAY 0.872340 (-3925 -175);
PAINT GREEN (-3925 -175);
DISPLAY INVISIBLE (-3925 -175);
FORCEPROP 1 LAST OFFPAGE TRUE
J 0
(-3725 -200);
DISPLAY 0.872340 (-3725 -200);
PAINT GREEN (-3725 -200);
DISPLAY INVISIBLE (-3725 -200);
FORCEPROP 2 LAST CDS_LIB standard
J 0
(-4050 -75);
DISPLAY INVISIBLE (-4050 -75);
FORCEPROP 2 LAST PATH I3
J 0
(-4350 -25);
DISPLAY 1.021277 (-4350 -25);
DISPLAY INVISIBLE (-4350 -25);
FORCEADD UNIVERSAL_GND..1
(-725 -2925);
FORCEPROP 3 LASTPIN (-725 -2875) SIG_NAME GND\g
J 0
(-715 -2865);
DISPLAY 0.659574 (-715 -2865);
PAINT MONO (-715 -2865);
DISPLAY INVISIBLE (-715 -2865);
FORCEPROP 1 LAST HDL_POWER GND
J 1
(-700 -3000);
DISPLAY 0.872340 (-700 -3000);
PAINT GREEN (-700 -3000);
DISPLAY INVISIBLE (-700 -3000);
FORCEPROP 2 LAST CDS_LIB logical_power
J 0
(-725 -2925);
PAINT MONO (-725 -2925);
DISPLAY INVISIBLE (-725 -2925);
FORCEPROP 1 LAST PATH I30
J 0
(-650 -2925);
DISPLAY 0.872340 (-650 -2925);
PAINT AQUA (-650 -2925);
DISPLAY INVISIBLE (-650 -2925);
FORCEADD Q_CAP..1
(-725 -2625);
FORCEPROP 1 LAST PART_NUMBER CH4104K1B00
J 0
(-675 -2800);
DISPLAY 0.617021 (-675 -2800);
PAINT BLUE (-675 -2800);
DISPLAY INVISIBLE (-675 -2800);
FORCEPROP 1 LAST TOLERANCE 10%
J 0
(-675 -2650);
DISPLAY 0.617021 (-675 -2650);
PAINT SKYBLUE (-675 -2650);
FORCEPROP 1 LAST MATERIAL X7R
J 0
(-675 -2700);
DISPLAY 0.617021 (-675 -2700);
PAINT SKYBLUE (-675 -2700);
FORCEPROP 1 LAST VALUE 0.1UF
J 0
(-675 -2550);
DISPLAY 0.617021 (-675 -2550);
PAINT SKYBLUE (-675 -2550);
FORCEPROP 1 LAST VOLTAGE 25V
J 0
(-675 -2600);
DISPLAY 0.617021 (-675 -2600);
PAINT SKYBLUE (-675 -2600);
FORCEPROP 1 LAST PACK_TYPE 0402
J 0
(-675 -2750);
DISPLAY 0.617021 (-675 -2750);
PAINT SKYBLUE (-675 -2750);
FORCEPROP 1 LAST LOCATION PC548
J 0
(-675 -2500);
DISPLAY 0.617021 (-675 -2500);
PAINT AQUA (-675 -2500);
FORCEPROP 1 LASTPIN (-725 -2525) $PN 1
J 0
(-715 -2545);
DISPLAY 0.617021 (-715 -2545);
PAINT MONO (-715 -2545);
FORCEPROP 1 LASTPIN (-725 -2725) $PN 2
J 0
(-715 -2745);
DISPLAY 0.617021 (-715 -2745);
PAINT MONO (-715 -2745);
FORCEPROP 2 LAST CDS_LIB pure_quanta
J 0
(-725 -2625);
DISPLAY INVISIBLE (-725 -2625);
FORCEPROP 1 LAST PATH I31
J 0
(-675 -2475);
DISPLAY 0.978723 (-675 -2475);
PAINT WHITE (-675 -2475);
DISPLAY INVISIBLE (-675 -2475);
FORCEPROP 1 LAST LOCATION PC548
J 0
(-675 -2450);
DISPLAY 1.021277 (-675 -2450);
PAINT AQUA (-675 -2450);
DISPLAY INVISIBLE (-675 -2450);
FORCEPROP 0 LAST $SEC 1
J 0
(-675 -2450);
DISPLAY 0.680851 (-675 -2450);
PAINT MONO (-675 -2450);
DISPLAY INVISIBLE (-675 -2450);
FORCEPROP 0 LAST CDS_SEC 1
J 0
(-675 -2450);
DISPLAY 1.021277 (-675 -2450);
DISPLAY INVISIBLE (-675 -2450);
FORCEADD UNIVERSAL_GND..1
(-575 -2650);
FORCEPROP 3 LASTPIN (-575 -2600) SIG_NAME GND\g
J 0
(-565 -2590);
DISPLAY 0.659574 (-565 -2590);
PAINT MONO (-565 -2590);
DISPLAY INVISIBLE (-565 -2590);
FORCEPROP 1 LAST HDL_POWER GND
J 1
(-550 -2725);
DISPLAY 0.872340 (-550 -2725);
PAINT GREEN (-550 -2725);
DISPLAY INVISIBLE (-550 -2725);
FORCEPROP 2 LAST CDS_LIB logical_power
J 0
(-575 -2650);
PAINT MONO (-575 -2650);
DISPLAY INVISIBLE (-575 -2650);
FORCEPROP 1 LAST PATH I32
J 0
(-500 -2650);
DISPLAY 0.872340 (-500 -2650);
PAINT AQUA (-500 -2650);
DISPLAY INVISIBLE (-500 -2650);
FORCEADD RAA229126GNPHA0..1
(225 275);
FORCEPROP 1 LAST PART_NUMBER AL229126000
J 0
(-325 3225);
DISPLAY 0.617021 (-325 3225);
PAINT BLUE (-325 3225);
DISPLAY INVISIBLE (-325 3225);
FORCEPROP 2 LAST VALUE RAA229126GNP#HA0
J 0
(200 3225);
DISPLAY 0.617021 (200 3225);
PAINT SKYBLUE (200 3225);
FORCEPROP 1 LAST MATERIAL IC
J 0
(-325 3150);
DISPLAY 0.617021 (-325 3150);
PAINT SKYBLUE (-325 3150);
FORCEPROP 2 LAST PART_TYPE SMLF
J 0
(200 3275);
DISPLAY 0.638298 (200 3275);
FORCEPROP 1 LAST LOCATION PU29
J 0
(-325 3300);
DISPLAY 0.617021 (-325 3300);
PAINT AQUA (-325 3300);
FORCEPROP 2 LASTPIN (-475 -2075) $PN 42
J 2
(-485 -2065);
DISPLAY 0.617021 (-485 -2065);
PAINT MONO (-485 -2065);
FORCEPROP 2 LASTPIN (-475 -975) $PN 41
J 2
(-485 -965);
DISPLAY 0.617021 (-485 -965);
PAINT MONO (-485 -965);
FORCEPROP 2 LASTPIN (875 -1375) $PN 38
J 0
(885 -1365);
DISPLAY 0.617021 (885 -1365);
PAINT MONO (885 -1365);
FORCEPROP 2 LASTPIN (875 -1075) $PN 37
J 0
(885 -1065);
DISPLAY 0.617021 (885 -1065);
PAINT MONO (885 -1065);
FORCEPROP 2 LASTPIN (875 -775) $PN 36
J 0
(885 -765);
DISPLAY 0.617021 (885 -765);
PAINT MONO (885 -765);
FORCEPROP 2 LASTPIN (875 -475) $PN 35
J 0
(885 -465);
DISPLAY 0.617021 (885 -465);
PAINT MONO (885 -465);
FORCEPROP 2 LASTPIN (875 -175) $PN 34
J 0
(885 -165);
DISPLAY 0.617021 (885 -165);
PAINT MONO (885 -165);
FORCEPROP 2 LASTPIN (875 125) $PN 33
J 0
(885 135);
DISPLAY 0.617021 (885 135);
PAINT MONO (885 135);
FORCEPROP 2 LASTPIN (875 425) $PN 32
J 0
(885 435);
DISPLAY 0.617021 (885 435);
PAINT MONO (885 435);
FORCEPROP 2 LASTPIN (875 725) $PN 31
J 0
(885 735);
DISPLAY 0.617021 (885 735);
PAINT MONO (885 735);
FORCEPROP 2 LASTPIN (875 1025) $PN 30
J 0
(885 1035);
DISPLAY 0.617021 (885 1035);
PAINT MONO (885 1035);
FORCEPROP 2 LASTPIN (875 1325) $PN 29
J 0
(885 1335);
DISPLAY 0.617021 (885 1335);
PAINT MONO (885 1335);
FORCEPROP 2 LASTPIN (875 1625) $PN 28
J 0
(885 1635);
DISPLAY 0.617021 (885 1635);
PAINT MONO (885 1635);
FORCEPROP 2 LASTPIN (875 1925) $PN 27
J 0
(885 1935);
DISPLAY 0.617021 (885 1935);
PAINT MONO (885 1935);
FORCEPROP 2 LASTPIN (-475 2875) $PN 17
J 2
(-485 2885);
DISPLAY 0.617021 (-485 2885);
PAINT MONO (-485 2885);
FORCEPROP 2 LASTPIN (-475 -1375) $PN 24
J 2
(-485 -1365);
DISPLAY 0.617021 (-485 -1365);
PAINT MONO (-485 -1365);
FORCEPROP 2 LASTPIN (-475 -1225) $PN 19
J 2
(-485 -1215);
DISPLAY 0.617021 (-485 -1215);
PAINT MONO (-485 -1215);
FORCEPROP 2 LASTPIN (-475 1575) $PN 15
J 2
(-485 1585);
DISPLAY 0.617021 (-485 1585);
PAINT MONO (-485 1585);
FORCEPROP 2 LASTPIN (-475 2275) $PN 23
J 2
(-485 2285);
DISPLAY 0.617021 (-485 2285);
PAINT MONO (-485 2285);
FORCEPROP 2 LASTPIN (-475 -825) $PN 18
J 2
(-485 -815);
DISPLAY 0.617021 (-485 -815);
PAINT MONO (-485 -815);
FORCEPROP 2 LASTPIN (-475 3025) $PN 16
J 2
(-485 3035);
DISPLAY 0.617021 (-485 3035);
PAINT MONO (-485 3035);
FORCEPROP 2 LASTPIN (-475 -1775) $PN 20
J 2
(-485 -1765);
DISPLAY 0.617021 (-485 -1765);
PAINT MONO (-485 -1765);
FORCEPROP 2 LASTPIN (-475 1875) $PN 14
J 2
(-485 1885);
DISPLAY 0.617021 (-485 1885);
PAINT MONO (-485 1885);
FORCEPROP 2 LASTPIN (-475 1725) $PN 13
J 2
(-485 1735);
DISPLAY 0.617021 (-485 1735);
PAINT MONO (-485 1735);
FORCEPROP 2 LASTPIN (875 -1275) $PN 1
J 0
(885 -1265);
DISPLAY 0.617021 (885 -1265);
PAINT MONO (885 -1265);
FORCEPROP 2 LASTPIN (875 -975) $PN 2
J 0
(885 -965);
DISPLAY 0.617021 (885 -965);
PAINT MONO (885 -965);
FORCEPROP 2 LASTPIN (875 -675) $PN 3
J 0
(885 -665);
DISPLAY 0.617021 (885 -665);
PAINT MONO (885 -665);
FORCEPROP 2 LASTPIN (875 -375) $PN 4
J 0
(885 -365);
DISPLAY 0.617021 (885 -365);
PAINT MONO (885 -365);
FORCEPROP 2 LASTPIN (875 -75) $PN 5
J 0
(885 -65);
DISPLAY 0.617021 (885 -65);
PAINT MONO (885 -65);
FORCEPROP 2 LASTPIN (875 225) $PN 6
J 0
(885 235);
DISPLAY 0.617021 (885 235);
PAINT MONO (885 235);
FORCEPROP 2 LASTPIN (875 525) $PN 7
J 0
(885 535);
DISPLAY 0.617021 (885 535);
PAINT MONO (885 535);
FORCEPROP 2 LASTPIN (875 825) $PN 8
J 0
(885 835);
DISPLAY 0.617021 (885 835);
PAINT MONO (885 835);
FORCEPROP 2 LASTPIN (875 1125) $PN 9
J 0
(885 1135);
DISPLAY 0.617021 (885 1135);
PAINT MONO (885 1135);
FORCEPROP 2 LASTPIN (875 1425) $PN 10
J 0
(885 1435);
DISPLAY 0.617021 (885 1435);
PAINT MONO (885 1435);
FORCEPROP 2 LASTPIN (875 1725) $PN 11
J 0
(885 1735);
DISPLAY 0.617021 (885 1735);
PAINT MONO (885 1735);
FORCEPROP 2 LASTPIN (875 2025) $PN 12
J 0
(885 2035);
DISPLAY 0.617021 (885 2035);
PAINT MONO (885 2035);
FORCEPROP 2 LASTPIN (-475 725) $PN 26
J 2
(-485 735);
DISPLAY 0.617021 (-485 735);
PAINT MONO (-485 735);
FORCEPROP 2 LASTPIN (-475 -375) $PN 39
J 2
(-485 -365);
DISPLAY 0.617021 (-485 -365);
PAINT MONO (-485 -365);
FORCEPROP 2 LASTPIN (-475 2575) $PN 21
J 2
(-485 2585);
DISPLAY 0.617021 (-485 2585);
PAINT MONO (-485 2585);
FORCEPROP 2 LASTPIN (-475 2425) $PN 22
J 2
(-485 2435);
DISPLAY 0.617021 (-485 2435);
PAINT MONO (-485 2435);
FORCEPROP 2 LASTPIN (875 -2175) $PN 43
J 0
(885 -2165);
DISPLAY 0.617021 (885 -2165);
PAINT MONO (885 -2165);
FORCEPROP 2 LASTPIN (875 -1875) $PN 44
J 0
(885 -1865);
DISPLAY 0.617021 (885 -1865);
PAINT MONO (885 -1865);
FORCEPROP 2 LASTPIN (-475 -2525) $PN TH
J 2
(-485 -2515);
DISPLAY 0.617021 (-485 -2515);
PAINT MONO (-485 -2515);
FORCEPROP 2 LASTPIN (875 3025) $PN 47
J 0
(885 3035);
DISPLAY 0.617021 (885 3035);
PAINT MONO (885 3035);
FORCEPROP 2 LASTPIN (875 2725) $PN 48
J 0
(885 2735);
DISPLAY 0.617021 (885 2735);
PAINT MONO (885 2735);
FORCEPROP 2 LASTPIN (-475 -2425) $PN 46
J 2
(-485 -2415);
DISPLAY 0.617021 (-485 -2415);
PAINT MONO (-485 -2415);
FORCEPROP 2 LASTPIN (-475 -2325) $PN 45
J 2
(-485 -2315);
DISPLAY 0.617021 (-485 -2315);
PAINT MONO (-485 -2315);
FORCEPROP 2 LASTPIN (-475 975) $PN 25
J 2
(-485 985);
DISPLAY 0.617021 (-485 985);
PAINT MONO (-485 985);
FORCEPROP 2 LASTPIN (-475 -125) $PN 40
J 2
(-485 -115);
DISPLAY 0.617021 (-485 -115);
PAINT MONO (-485 -115);
FORCEPROP 1 LAST CDS_LMAN_SYM_OUTLINE -550,2850,500,-2850
J 0
(225 275);
DISPLAY 0.468085 (225 275);
PAINT GREEN (225 275);
DISPLAY INVISIBLE (225 275);
FORCEPROP 1 LAST NEEDS_NO_SIZE TRUE
J 0
(225 275);
DISPLAY 0.723404 (225 275);
PAINT GREEN (225 275);
DISPLAY INVISIBLE (225 275);
FORCEPROP 2 LAST CDS_LIB pure_quanta
J 0
(225 275);
DISPLAY INVISIBLE (225 275);
FORCEPROP 2 LAST SEC_TYPE 
J 0
(-325 3350);
DISPLAY 1.021277 (-325 3350);
DISPLAY INVISIBLE (-325 3350);
FORCEPROP 1 LAST PATH I33
J 0
(225 275);
DISPLAY 0.723404 (225 275);
PAINT GREEN (225 275);
DISPLAY INVISIBLE (225 275);
FORCEPROP 2 LAST SEC 1
J 0
(-325 3350);
DISPLAY 0.680851 (-325 3350);
PAINT MONO (-325 3350);
DISPLAY INVISIBLE (-325 3350);
FORCEADD Q_CAP..2
(-1200 -1500);
FORCEPROP 1 LAST PART_NUMBER TMP_QCH21006JB10
J 1
(-925 -1550);
DISPLAY 0.617021 (-925 -1550);
PAINT BLUE (-925 -1550);
DISPLAY INVISIBLE (-925 -1550);
FORCEPROP 1 LAST VALUE 1000PF
J 2
(-875 -1500);
DISPLAY 0.617021 (-875 -1500);
PAINT SKYBLUE (-875 -1500);
FORCEPROP 1 LAST PACK_TYPE 0402
J 1
(-575 -1500);
DISPLAY 0.617021 (-575 -1500);
PAINT SKYBLUE (-575 -1500);
FORCEPROP 1 LAST VOLTAGE 50V
J 0
(-850 -1500);
DISPLAY 0.617021 (-850 -1500);
PAINT SKYBLUE (-850 -1500);
FORCEPROP 1 LAST MATERIAL X7R
J 0
(-725 -1500);
DISPLAY 0.617021 (-725 -1500);
PAINT SKYBLUE (-725 -1500);
FORCEPROP 1 LAST TOLERANCE 5%
J 2
(-550 -1550);
DISPLAY 0.617021 (-550 -1550);
PAINT SKYBLUE (-550 -1550);
FORCEPROP 1 LAST LOCATION C2446
J 1
(-1400 -1500);
DISPLAY 0.617021 (-1400 -1500);
PAINT AQUA (-1400 -1500);
FORCEPROP 1 LASTPIN (-1300 -1500) $PN 1
J 0
(-1310 -1485);
DISPLAY 0.787234 (-1310 -1485);
PAINT MONO (-1310 -1485);
FORCEPROP 1 LASTPIN (-1100 -1500) $PN 2
J 0
(-1115 -1485);
DISPLAY 0.787234 (-1115 -1485);
PAINT MONO (-1115 -1485);
FORCEPROP 2 LAST SEC_TYPE 0402
J 0
(-1200 -1250);
DISPLAY 1.021277 (-1200 -1250);
DISPLAY INVISIBLE (-1200 -1250);
FORCEPROP 2 LAST CDS_LIB pure_quanta
J 0
(-1200 -1500);
DISPLAY INVISIBLE (-1200 -1500);
FORCEPROP 1 LAST PATH I34
J 0
(-1200 -1300);
DISPLAY 0.978723 (-1200 -1300);
PAINT WHITE (-1200 -1300);
DISPLAY INVISIBLE (-1200 -1300);
FORCEPROP 1 LAST LOCATION C2446
J 0
(-1250 -1400);
DISPLAY 1.021277 (-1250 -1400);
PAINT AQUA (-1250 -1400);
DISPLAY INVISIBLE (-1250 -1400);
FORCEPROP 2 LAST SEC 1
J 0
(-1200 -1250);
DISPLAY 0.680851 (-1200 -1250);
PAINT MONO (-1200 -1250);
DISPLAY INVISIBLE (-1200 -1250);
FORCEADD Q_CAP..2
(-1200 -1625);
FORCEPROP 1 LAST PART_NUMBER TMP_QCH21006JB10
J 1
(-925 -1675);
DISPLAY 0.617021 (-925 -1675);
PAINT BLUE (-925 -1675);
DISPLAY INVISIBLE (-925 -1675);
FORCEPROP 1 LAST VOLTAGE 50V
J 0
(-850 -1625);
DISPLAY 0.617021 (-850 -1625);
PAINT SKYBLUE (-850 -1625);
FORCEPROP 1 LAST VALUE 1000PF
J 2
(-875 -1625);
DISPLAY 0.617021 (-875 -1625);
PAINT SKYBLUE (-875 -1625);
FORCEPROP 1 LAST PACK_TYPE 0402
J 1
(-650 -1700);
DISPLAY 0.617021 (-650 -1700);
PAINT SKYBLUE (-650 -1700);
FORCEPROP 1 LAST TOLERANCE 5%
J 2
(-550 -1675);
DISPLAY 0.617021 (-550 -1675);
PAINT SKYBLUE (-550 -1675);
FORCEPROP 1 LAST MATERIAL EMPTY
J 0
(-725 -1625);
DISPLAY 0.617021 (-725 -1625);
PAINT RED (-725 -1625);
FORCEPROP 1 LAST LOCATION C2447
J 1
(-1400 -1625);
DISPLAY 0.617021 (-1400 -1625);
PAINT AQUA (-1400 -1625);
FORCEPROP 1 LASTPIN (-1300 -1625) $PN 1
J 0
(-1310 -1610);
DISPLAY 0.617021 (-1310 -1610);
PAINT MONO (-1310 -1610);
FORCEPROP 1 LASTPIN (-1100 -1625) $PN 2
J 0
(-1115 -1610);
DISPLAY 0.617021 (-1115 -1610);
PAINT MONO (-1115 -1610);
FORCEPROP 2 LAST CDS_LIB pure_quanta
J 0
(-1200 -1625);
DISPLAY INVISIBLE (-1200 -1625);
FORCEPROP 1 LAST PATH I35
J 0
(-1200 -1425);
DISPLAY 0.978723 (-1200 -1425);
PAINT WHITE (-1200 -1425);
DISPLAY INVISIBLE (-1200 -1425);
FORCEPROP 1 LAST LOCATION C2447
J 0
(-1250 -1525);
DISPLAY 1.021277 (-1250 -1525);
PAINT AQUA (-1250 -1525);
DISPLAY INVISIBLE (-1250 -1525);
FORCEPROP 0 LAST $SEC 1
J 0
(-1250 -1525);
DISPLAY 0.680851 (-1250 -1525);
PAINT MONO (-1250 -1525);
DISPLAY INVISIBLE (-1250 -1525);
FORCEPROP 0 LAST CDS_SEC 1
J 0
(-1250 -1525);
DISPLAY 1.021277 (-1250 -1525);
DISPLAY INVISIBLE (-1250 -1525);
FORCEADD Q_RES..1
(-1650 -825);
FORCEPROP 1 LAST PART_NUMBER CS00002JB13
J 0
(-1750 -775);
DISPLAY 0.489362 (-1750 -775);
PAINT BLUE (-1750 -775);
DISPLAY INVISIBLE (-1750 -775);
FORCEPROP 1 LAST VALUE 0
J 2
(-1500 -825);
DISPLAY 0.489362 (-1500 -825);
PAINT SKYBLUE (-1500 -825);
FORCEPROP 1 LAST TOLERANCE 5%
J 0
(-1475 -825);
DISPLAY 0.489362 (-1475 -825);
PAINT SKYBLUE (-1475 -825);
FORCEPROP 1 LAST PACK_TYPE 0402LF
J 0
(-1750 -725);
DISPLAY 0.489362 (-1750 -725);
PAINT SKYBLUE (-1750 -725);
FORCEPROP 1 LAST WATTAGE 1/16W
J 2
(-1475 -725);
DISPLAY 0.489362 (-1475 -725);
PAINT SKYBLUE (-1475 -725);
FORCEPROP 1 LAST MATERIAL CHIP
J 0
(-1400 -825);
DISPLAY 0.489362 (-1400 -825);
PAINT SKYBLUE (-1400 -825);
FORCEPROP 1 LAST LOCATION R2523
J 0
(-1875 -825);
DISPLAY 0.617021 (-1875 -825);
PAINT AQUA (-1875 -825);
FORCEPROP 1 LASTPIN (-1750 -825) $PN 1
J 0
(-1738 -813);
DISPLAY 0.787234 (-1738 -813);
PAINT MONO (-1738 -813);
FORCEPROP 1 LASTPIN (-1550 -825) $PN 2
J 0
(-1588 -813);
DISPLAY 0.787234 (-1588 -813);
PAINT MONO (-1588 -813);
FORCEPROP 2 LAST CDS_LIB pure_quanta
J 0
(-1650 -825);
DISPLAY INVISIBLE (-1650 -825);
FORCEPROP 1 LAST PATH I36
J 0
(-1700 -675);
DISPLAY 0.978723 (-1700 -675);
PAINT WHITE (-1700 -675);
DISPLAY INVISIBLE (-1700 -675);
FORCEPROP 0 LAST $SEC 1
J 0
(-1475 -700);
DISPLAY 0.680851 (-1475 -700);
PAINT MONO (-1475 -700);
DISPLAY INVISIBLE (-1475 -700);
FORCEPROP 0 LAST CDS_SEC 1
J 0
(-1475 -700);
DISPLAY 1.021277 (-1475 -700);
DISPLAY INVISIBLE (-1475 -700);
FORCEADD Q_RES..1
(-1775 -75);
FORCEPROP 1 LAST PART_NUMBER CS00002JB13
J 0
(-1650 -25);
DISPLAY 0.617021 (-1650 -25);
PAINT BLUE (-1650 -25);
DISPLAY INVISIBLE (-1650 -25);
FORCEPROP 1 LAST WATTAGE 1/16W
J 2
(-1400 25);
DISPLAY 0.617021 (-1400 25);
PAINT SKYBLUE (-1400 25);
FORCEPROP 1 LAST MATERIAL CHIP
J 0
(-1650 25);
DISPLAY 0.617021 (-1650 25);
PAINT SKYBLUE (-1650 25);
FORCEPROP 1 LAST TOLERANCE 5%
J 0
(-1600 -75);
DISPLAY 0.617021 (-1600 -75);
PAINT SKYBLUE (-1600 -75);
FORCEPROP 1 LAST VALUE 0
J 2
(-1625 -75);
DISPLAY 0.617021 (-1625 -75);
PAINT SKYBLUE (-1625 -75);
FORCEPROP 1 LAST PACK_TYPE 0402LF
J 0
(-1525 -75);
DISPLAY 0.617021 (-1525 -75);
PAINT SKYBLUE (-1525 -75);
FORCEPROP 1 LAST LOCATION PR242
J 0
(-1975 -75);
DISPLAY 0.617021 (-1975 -75);
PAINT AQUA (-1975 -75);
FORCEPROP 1 LASTPIN (-1875 -75) $PN 1
J 0
(-1863 -63);
DISPLAY 0.617021 (-1863 -63);
PAINT MONO (-1863 -63);
FORCEPROP 1 LASTPIN (-1675 -75) $PN 2
J 0
(-1713 -63);
DISPLAY 0.617021 (-1713 -63);
PAINT MONO (-1713 -63);
FORCEPROP 2 LAST CDS_LIB pure_quanta
J 0
(-1775 -75);
DISPLAY INVISIBLE (-1775 -75);
FORCEPROP 1 LAST PATH I37
J 0
(-1825 75);
DISPLAY 0.978723 (-1825 75);
PAINT WHITE (-1825 75);
DISPLAY INVISIBLE (-1825 75);
FORCEPROP 1 LAST LOCATION PR242
J 0
(-1825 25);
DISPLAY 1.021277 (-1825 25);
PAINT AQUA (-1825 25);
DISPLAY INVISIBLE (-1825 25);
FORCEPROP 0 LAST $SEC 1
J 0
(-1825 25);
DISPLAY 0.680851 (-1825 25);
PAINT MONO (-1825 25);
DISPLAY INVISIBLE (-1825 25);
FORCEPROP 0 LAST CDS_SEC 1
J 0
(-1825 25);
DISPLAY 1.021277 (-1825 25);
DISPLAY INVISIBLE (-1825 25);
FORCEADD Q_CAP..1
(-1325 -250);
FORCEPROP 1 LAST PART_NUMBER TMP_QCH2336K1B12
J 0
(-1275 -425);
DISPLAY 0.617021 (-1275 -425);
PAINT BLUE (-1275 -425);
DISPLAY INVISIBLE (-1275 -425);
FORCEPROP 1 LAST VOLTAGE 50V
J 0
(-1275 -225);
DISPLAY 0.617021 (-1275 -225);
PAINT SKYBLUE (-1275 -225);
FORCEPROP 1 LAST MATERIAL X7R
J 0
(-1275 -325);
DISPLAY 0.617021 (-1275 -325);
PAINT SKYBLUE (-1275 -325);
FORCEPROP 1 LAST PACK_TYPE 0402
J 0
(-1275 -375);
DISPLAY 0.617021 (-1275 -375);
PAINT SKYBLUE (-1275 -375);
FORCEPROP 1 LAST TOLERANCE 10%
J 0
(-1275 -275);
DISPLAY 0.617021 (-1275 -275);
PAINT SKYBLUE (-1275 -275);
FORCEPROP 1 LAST VALUE 3300PF
J 0
(-1275 -175);
DISPLAY 0.617021 (-1275 -175);
PAINT SKYBLUE (-1275 -175);
FORCEPROP 1 LAST LOCATION PC422
J 0
(-1275 -125);
DISPLAY 0.617021 (-1275 -125);
PAINT AQUA (-1275 -125);
FORCEPROP 1 LASTPIN (-1325 -150) $PN 1
J 0
(-1315 -170);
DISPLAY 0.617021 (-1315 -170);
PAINT MONO (-1315 -170);
FORCEPROP 1 LASTPIN (-1325 -350) $PN 2
J 0
(-1315 -370);
DISPLAY 0.617021 (-1315 -370);
PAINT MONO (-1315 -370);
FORCEPROP 2 LAST CDS_LIB pure_quanta
J 0
(-1325 -250);
DISPLAY INVISIBLE (-1325 -250);
FORCEPROP 1 LAST PATH I38
J 0
(-1275 -100);
DISPLAY 0.978723 (-1275 -100);
PAINT WHITE (-1275 -100);
DISPLAY INVISIBLE (-1275 -100);
FORCEPROP 1 LAST LOCATION PC422
J 0
(-1275 -125);
DISPLAY 1.021277 (-1275 -125);
PAINT AQUA (-1275 -125);
DISPLAY INVISIBLE (-1275 -125);
FORCEPROP 0 LAST $SEC 1
J 0
(-1275 -125);
DISPLAY 0.680851 (-1275 -125);
PAINT MONO (-1275 -125);
DISPLAY INVISIBLE (-1275 -125);
FORCEPROP 0 LAST CDS_SEC 1
J 0
(-1275 -125);
DISPLAY 1.021277 (-1275 -125);
DISPLAY INVISIBLE (-1275 -125);
FORCEADD UNIVERSAL_GND..1
R 1
(-500 -1500);
FORCEPROP 3 LASTPIN (-550 -1500) SIG_NAME GND\g
J 0
(-540 -1490);
DISPLAY 0.659574 (-540 -1490);
PAINT MONO (-540 -1490);
DISPLAY INVISIBLE (-540 -1490);
FORCEPROP 1 LAST HDL_POWER GND
R 1
J 1
(-425 -1475);
DISPLAY 0.872340 (-425 -1475);
PAINT GREEN (-425 -1475);
DISPLAY INVISIBLE (-425 -1475);
FORCEPROP 2 LAST CDS_LIB logical_power
J 0
(-500 -1500);
DISPLAY INVISIBLE (-500 -1500);
FORCEPROP 1 LAST PATH I39
R 1
J 0
(-500 -1425);
DISPLAY 0.872340 (-500 -1425);
PAINT AQUA (-500 -1425);
DISPLAY INVISIBLE (-500 -1425);
FORCEADD Q_RES..1
(-3100 -2075);
FORCEPROP 1 LAST PART_NUMBER CS32802FB05
J 0
(-3200 -2000);
DISPLAY 0.617021 (-3200 -2000);
PAINT BLUE (-3200 -2000);
DISPLAY INVISIBLE (-3200 -2000);
FORCEPROP 1 LAST TOLERANCE 1%
J 0
(-2850 -2075);
DISPLAY 0.617021 (-2850 -2075);
PAINT SKYBLUE (-2850 -2075);
FORCEPROP 1 LAST MATERIAL EMPTY
J 0
(-3200 -1950);
DISPLAY 0.617021 (-3200 -1950);
PAINT RED (-3200 -1950);
FORCEPROP 1 LAST VALUE 28K
J 2
(-2875 -2075);
DISPLAY 0.617021 (-2875 -2075);
PAINT SKYBLUE (-2875 -2075);
FORCEPROP 1 LAST WATTAGE 1/16W
J 2
(-2875 -1950);
DISPLAY 0.617021 (-2875 -1950);
PAINT SKYBLUE (-2875 -1950);
FORCEPROP 1 LAST PACK_TYPE 0402LF
J 0
(-2775 -2075);
DISPLAY 0.617021 (-2775 -2075);
PAINT SKYBLUE (-2775 -2075);
FORCEPROP 1 LAST LOCATION PR306
J 0
(-3325 -2075);
DISPLAY 0.617021 (-3325 -2075);
PAINT AQUA (-3325 -2075);
FORCEPROP 1 LASTPIN (-3200 -2075) $PN 1
J 0
(-3188 -2063);
DISPLAY 0.617021 (-3188 -2063);
PAINT MONO (-3188 -2063);
FORCEPROP 1 LASTPIN (-3000 -2075) $PN 2
J 0
(-3038 -2063);
DISPLAY 0.617021 (-3038 -2063);
PAINT MONO (-3038 -2063);
FORCEPROP 2 LAST CDS_LIB pure_quanta
J 0
(-3100 -2075);
DISPLAY INVISIBLE (-3100 -2075);
FORCEPROP 1 LAST PATH I4
J 0
(-3150 -1925);
DISPLAY 0.978723 (-3150 -1925);
PAINT WHITE (-3150 -1925);
DISPLAY INVISIBLE (-3150 -1925);
FORCEPROP 1 LAST LOCATION PR306
J 0
(-3175 -1950);
DISPLAY 1.021277 (-3175 -1950);
PAINT AQUA (-3175 -1950);
DISPLAY INVISIBLE (-3175 -1950);
FORCEPROP 0 LAST $SEC 1
J 0
(-3175 -1950);
DISPLAY 0.680851 (-3175 -1950);
PAINT MONO (-3175 -1950);
DISPLAY INVISIBLE (-3175 -1950);
FORCEPROP 0 LAST CDS_SEC 1
J 0
(-3175 -1950);
DISPLAY 1.021277 (-3175 -1950);
DISPLAY INVISIBLE (-3175 -1950);
FORCEADD UNIVERSAL_GND..1
R 1
(-500 -1625);
FORCEPROP 3 LASTPIN (-550 -1625) SIG_NAME GND\g
J 0
(-540 -1615);
DISPLAY 0.659574 (-540 -1615);
PAINT MONO (-540 -1615);
DISPLAY INVISIBLE (-540 -1615);
FORCEPROP 1 LAST HDL_POWER GND
R 1
J 1
(-425 -1600);
DISPLAY 0.872340 (-425 -1600);
PAINT GREEN (-425 -1600);
DISPLAY INVISIBLE (-425 -1600);
FORCEPROP 2 LAST CDS_LIB logical_power
J 0
(-500 -1625);
DISPLAY INVISIBLE (-500 -1625);
FORCEPROP 1 LAST PATH I40
R 1
J 0
(-500 -1550);
DISPLAY 0.872340 (-500 -1550);
PAINT AQUA (-500 -1550);
DISPLAY INVISIBLE (-500 -1550);
FORCEADD OFFPAGE..1
(-3975 650);
FORCEPROP 2 LAST $XR0 47 
J 0
(-4256 650);
DISPLAY 0.638298 (-4256 650);
PAINT MONO (-4256 650);
FORCEPROP 1 LAST COMMENT_BODY TRUE
J 0
(-3850 550);
DISPLAY 0.872340 (-3850 550);
PAINT GREEN (-3850 550);
DISPLAY INVISIBLE (-3850 550);
FORCEPROP 1 LAST OFFPAGE TRUE
J 0
(-3650 525);
DISPLAY 0.872340 (-3650 525);
PAINT GREEN (-3650 525);
DISPLAY INVISIBLE (-3650 525);
FORCEPROP 2 LAST CDS_LIB standard
J 0
(-3975 650);
DISPLAY INVISIBLE (-3975 650);
FORCEPROP 2 LAST PATH I41
J 0
(-4250 700);
DISPLAY 1.021277 (-4250 700);
DISPLAY INVISIBLE (-4250 700);
FORCEADD OFFPAGE..1
(-3975 1025);
FORCEPROP 2 LAST $XR0 47 
J 0
(-4256 1025);
DISPLAY 0.638298 (-4256 1025);
PAINT MONO (-4256 1025);
FORCEPROP 1 LAST COMMENT_BODY TRUE
J 0
(-3850 925);
DISPLAY 0.872340 (-3850 925);
PAINT GREEN (-3850 925);
DISPLAY INVISIBLE (-3850 925);
FORCEPROP 1 LAST OFFPAGE TRUE
J 0
(-3650 900);
DISPLAY 0.872340 (-3650 900);
PAINT GREEN (-3650 900);
DISPLAY INVISIBLE (-3650 900);
FORCEPROP 2 LAST CDS_LIB standard
J 0
(-3975 1025);
DISPLAY INVISIBLE (-3975 1025);
FORCEPROP 2 LAST PATH I42
J 0
(-4250 1075);
DISPLAY 1.021277 (-4250 1075);
DISPLAY INVISIBLE (-4250 1075);
FORCEADD OFFPAGE..6
(-3200 1725);
FORCEPROP 2 LAST $XR1 266 
J 0
(-3600 1725);
DISPLAY 0.638298 (-3600 1725);
PAINT MONO (-3600 1725);
FORCEPROP 2 LAST $XR0 241 
J 0
(-3480 1725);
DISPLAY 0.638298 (-3480 1725);
PAINT MONO (-3480 1725);
FORCEPROP 1 LAST COMMENT_BODY TRUE
J 0
(-3100 1650);
DISPLAY 0.872340 (-3100 1650);
PAINT GREEN (-3100 1650);
DISPLAY INVISIBLE (-3100 1650);
FORCEPROP 1 LAST OFFPAGE TRUE
J 0
(-2875 1600);
DISPLAY 0.872340 (-2875 1600);
PAINT GREEN (-2875 1600);
DISPLAY INVISIBLE (-2875 1600);
FORCEPROP 2 LAST CDS_LIB standard
J 0
(-3200 1725);
DISPLAY INVISIBLE (-3200 1725);
FORCEPROP 2 LAST PATH I43
J 0
(-3475 1775);
DISPLAY 1.021277 (-3475 1775);
DISPLAY INVISIBLE (-3475 1775);
FORCEADD OFFPAGE..1
(-3200 1875);
FORCEPROP 2 LAST $XR1 266 
J 0
(-3572 1875);
DISPLAY 0.638298 (-3572 1875);
PAINT MONO (-3572 1875);
FORCEPROP 2 LAST $XR0 241 
J 0
(-3452 1875);
DISPLAY 0.638298 (-3452 1875);
PAINT MONO (-3452 1875);
FORCEPROP 1 LAST COMMENT_BODY TRUE
J 0
(-3075 1775);
DISPLAY 0.872340 (-3075 1775);
PAINT GREEN (-3075 1775);
DISPLAY INVISIBLE (-3075 1775);
FORCEPROP 1 LAST OFFPAGE TRUE
J 0
(-2875 1750);
DISPLAY 0.872340 (-2875 1750);
PAINT GREEN (-2875 1750);
DISPLAY INVISIBLE (-2875 1750);
FORCEPROP 2 LAST CDS_LIB standard
J 0
(-3200 1875);
DISPLAY INVISIBLE (-3200 1875);
FORCEPROP 2 LAST PATH I44
J 0
(-3450 1925);
DISPLAY 1.021277 (-3450 1925);
DISPLAY INVISIBLE (-3450 1925);
FORCEADD Q_RES..1
(-2850 500);
FORCEPROP 1 LAST PART_NUMBER CS11002FB07
J 0
(-2725 550);
DISPLAY 0.617021 (-2725 550);
PAINT BLUE (-2725 550);
DISPLAY INVISIBLE (-2725 550);
FORCEPROP 1 LAST VALUE 100
J 2
(-2650 500);
DISPLAY 0.617021 (-2650 500);
PAINT SKYBLUE (-2650 500);
FORCEPROP 1 LAST MATERIAL CHIP
J 0
(-2725 600);
DISPLAY 0.617021 (-2725 600);
PAINT SKYBLUE (-2725 600);
FORCEPROP 1 LAST TOLERANCE 1%
J 0
(-2625 500);
DISPLAY 0.617021 (-2625 500);
PAINT SKYBLUE (-2625 500);
FORCEPROP 1 LAST WATTAGE 1/16W
J 2
(-2425 600);
DISPLAY 0.617021 (-2425 600);
PAINT SKYBLUE (-2425 600);
FORCEPROP 1 LAST PACK_TYPE 0402LF
J 0
(-2550 500);
DISPLAY 0.617021 (-2550 500);
PAINT SKYBLUE (-2550 500);
FORCEPROP 1 LAST LOCATION PR574
J 0
(-3075 500);
DISPLAY 0.617021 (-3075 500);
PAINT AQUA (-3075 500);
FORCEPROP 1 LASTPIN (-2950 500) $PN 1
J 0
(-2938 512);
DISPLAY 0.617021 (-2938 512);
FORCEPROP 1 LASTPIN (-2750 500) $PN 2
J 0
(-2788 512);
DISPLAY 0.617021 (-2788 512);
FORCEPROP 2 LAST CDS_LIB pure_quanta
J 0
(-2850 500);
PAINT MONO (-2850 500);
DISPLAY INVISIBLE (-2850 500);
FORCEPROP 1 LAST PATH I45
J 0
(-2900 650);
DISPLAY 0.978723 (-2900 650);
PAINT WHITE (-2900 650);
DISPLAY INVISIBLE (-2900 650);
FORCEPROP 2 LAST $SEC 1
J 0
(-2900 700);
DISPLAY 0.680851 (-2900 700);
PAINT MONO (-2900 700);
DISPLAY INVISIBLE (-2900 700);
FORCEPROP 2 LAST CDS_SEC 1
J 0
(-2900 700);
DISPLAY 1.021277 (-2900 700);
DISPLAY INVISIBLE (-2900 700);
FORCEADD Q_SHORT..1
(-2875 1025);
FORCEPROP 1 LAST PART_NUMBER SHORT6
J 0
(-2850 785);
DISPLAY 0.617021 (-2850 785);
PAINT BLUE (-2850 785);
DISPLAY INVISIBLE (-2850 785);
FORCEPROP 2 LAST PACK_TYPE SM
J 0
(-2850 875);
DISPLAY 0.617021 (-2850 875);
PAINT SKYBLUE (-2850 875);
FORCEPROP 1 LAST MATERIAL EMPTY
J 0
(-2850 835);
DISPLAY 0.617021 (-2850 835);
PAINT RED (-2850 835);
FORCEPROP 1 LAST LOCATION PJ52
J 0
(-2975 880);
DISPLAY 0.617021 (-2975 880);
PAINT AQUA (-2975 880);
FORCEPROP 0 LASTPIN (-3000 1025) $PN 1
J 2
(-3010 1035);
DISPLAY 0.617021 (-3010 1035);
PAINT MONO (-3010 1035);
FORCEPROP 0 LASTPIN (-2750 1025) $PN 2
J 0
(-2740 1035);
DISPLAY 0.617021 (-2740 1035);
PAINT MONO (-2740 1035);
FORCEPROP 1 LAST NEEDS_NO_SIZE TRUE
J 0
(-2875 1025);
DISPLAY 0.468085 (-2875 1025);
PAINT GREEN (-2875 1025);
DISPLAY INVISIBLE (-2875 1025);
FORCEPROP 2 LAST CDS_LIB pure_quanta
J 0
(-2875 1025);
DISPLAY INVISIBLE (-2875 1025);
FORCEPROP 1 LAST PATH I46
J 0
(-2950 1230);
DISPLAY 0.723404 (-2950 1230);
PAINT GREEN (-2950 1230);
DISPLAY INVISIBLE (-2950 1230);
FORCEPROP 1 LAST LOCATION PJ52
J 0
(-2950 1275);
DISPLAY 1.021277 (-2950 1275);
PAINT AQUA (-2950 1275);
DISPLAY INVISIBLE (-2950 1275);
FORCEPROP 0 LAST $SEC 1
J 0
(-2950 1275);
DISPLAY 0.680851 (-2950 1275);
PAINT MONO (-2950 1275);
DISPLAY INVISIBLE (-2950 1275);
FORCEPROP 0 LAST CDS_SEC 1
J 0
(-2950 1275);
DISPLAY 1.021277 (-2950 1275);
DISPLAY INVISIBLE (-2950 1275);
FORCEADD UNIVERSAL_GND..1
(-2325 400);
FORCEPROP 3 LASTPIN (-2325 450) SIG_NAME GND\g
J 0
(-2315 460);
DISPLAY 0.659574 (-2315 460);
PAINT MONO (-2315 460);
DISPLAY INVISIBLE (-2315 460);
FORCEPROP 1 LAST HDL_POWER GND
J 1
(-2300 325);
DISPLAY 0.872340 (-2300 325);
PAINT GREEN (-2300 325);
DISPLAY INVISIBLE (-2300 325);
FORCEPROP 2 LAST CDS_LIB logical_power
J 0
(-2325 400);
PAINT MONO (-2325 400);
DISPLAY INVISIBLE (-2325 400);
FORCEPROP 1 LAST PATH I47
J 0
(-2250 400);
DISPLAY 0.872340 (-2250 400);
PAINT AQUA (-2250 400);
DISPLAY INVISIBLE (-2250 400);
FORCEADD VCC15..1
(-2300 225);
FORCEPROP 3 LASTPIN (-2300 175) SIG_NAME PVCCFA_EHV_FIVRA_CPU1\g
J 0
(-2290 185);
DISPLAY 0.659574 (-2290 185);
PAINT MONO (-2290 185);
DISPLAY INVISIBLE (-2290 185);
FORCEPROP 1 LAST HDL_POWER PVCCFA_EHV_FIVRA_CPU1
J 1
(-2300 275);
DISPLAY 0.617021 (-2300 275);
PAINT GREEN (-2300 275);
FORCEPROP 2 LAST CDS_LIB logical_power
J 0
(-2300 225);
DISPLAY INVISIBLE (-2300 225);
FORCEPROP 1 LAST PATH I48
J 0
(-2250 250);
DISPLAY 0.872340 (-2250 250);
PAINT AQUA (-2250 250);
DISPLAY INVISIBLE (-2250 250);
FORCEADD Q_RES..1
(-2800 1175);
FORCEPROP 1 LAST PART_NUMBER CS11002FB07
J 0
(-2675 1225);
DISPLAY 0.617021 (-2675 1225);
PAINT BLUE (-2675 1225);
DISPLAY INVISIBLE (-2675 1225);
FORCEPROP 1 LAST MATERIAL CHIP
J 0
(-2675 1275);
DISPLAY 0.617021 (-2675 1275);
PAINT SKYBLUE (-2675 1275);
FORCEPROP 1 LAST VALUE 100
J 2
(-2600 1175);
DISPLAY 0.617021 (-2600 1175);
PAINT SKYBLUE (-2600 1175);
FORCEPROP 1 LAST TOLERANCE 1%
J 0
(-2575 1175);
DISPLAY 0.617021 (-2575 1175);
PAINT SKYBLUE (-2575 1175);
FORCEPROP 1 LAST WATTAGE 1/16W
J 2
(-2375 1275);
DISPLAY 0.617021 (-2375 1275);
PAINT SKYBLUE (-2375 1275);
FORCEPROP 1 LAST PACK_TYPE 0402LF
J 0
(-2500 1175);
DISPLAY 0.617021 (-2500 1175);
PAINT SKYBLUE (-2500 1175);
FORCEPROP 1 LAST LOCATION PR578
J 0
(-3025 1175);
DISPLAY 0.617021 (-3025 1175);
PAINT AQUA (-3025 1175);
FORCEPROP 1 LASTPIN (-2900 1175) $PN 1
J 0
(-2888 1187);
DISPLAY 0.617021 (-2888 1187);
FORCEPROP 1 LASTPIN (-2700 1175) $PN 2
J 0
(-2738 1187);
DISPLAY 0.617021 (-2738 1187);
FORCEPROP 2 LAST CDS_LIB pure_quanta
J 0
(-2800 1175);
PAINT MONO (-2800 1175);
DISPLAY INVISIBLE (-2800 1175);
FORCEPROP 1 LAST PATH I49
J 0
(-2850 1325);
DISPLAY 0.978723 (-2850 1325);
PAINT WHITE (-2850 1325);
DISPLAY INVISIBLE (-2850 1325);
FORCEPROP 2 LAST $SEC 1
J 0
(-2850 1375);
DISPLAY 0.680851 (-2850 1375);
PAINT MONO (-2850 1375);
DISPLAY INVISIBLE (-2850 1375);
FORCEPROP 2 LAST CDS_SEC 1
J 0
(-2850 1375);
DISPLAY 1.021277 (-2850 1375);
DISPLAY INVISIBLE (-2850 1375);
FORCEADD UNIVERSAL_GND..1
(-2725 -2525);
FORCEPROP 3 LASTPIN (-2725 -2475) SIG_NAME GND\g
J 0
(-2715 -2465);
DISPLAY 0.659574 (-2715 -2465);
PAINT MONO (-2715 -2465);
DISPLAY INVISIBLE (-2715 -2465);
FORCEPROP 1 LAST HDL_POWER GND
J 1
(-2700 -2600);
DISPLAY 0.872340 (-2700 -2600);
PAINT GREEN (-2700 -2600);
DISPLAY INVISIBLE (-2700 -2600);
FORCEPROP 2 LAST CDS_LIB logical_power
J 0
(-2725 -2525);
PAINT MONO (-2725 -2525);
DISPLAY INVISIBLE (-2725 -2525);
FORCEPROP 1 LAST PATH I5
J 0
(-2650 -2525);
DISPLAY 0.872340 (-2650 -2525);
PAINT AQUA (-2650 -2525);
DISPLAY INVISIBLE (-2650 -2525);
FORCEADD VCC15..1
(-2300 1325);
FORCEPROP 3 LASTPIN (-2300 1275) SIG_NAME PVCCIN_CPU1\g
J 0
(-2290 1285);
DISPLAY 0.659574 (-2290 1285);
PAINT MONO (-2290 1285);
DISPLAY INVISIBLE (-2290 1285);
FORCEPROP 1 LAST HDL_POWER PVCCIN_CPU1
J 1
(-2300 1375);
DISPLAY 0.617021 (-2300 1375);
PAINT GREEN (-2300 1375);
FORCEPROP 2 LAST CDS_LIB logical_power
J 0
(-2300 1325);
DISPLAY INVISIBLE (-2300 1325);
FORCEPROP 1 LAST PATH I50
J 0
(-2250 1350);
DISPLAY 0.872340 (-2250 1350);
PAINT AQUA (-2250 1350);
DISPLAY INVISIBLE (-2250 1350);
FORCEADD OFFPAGE..6
(-3375 2425);
FORCEPROP 2 LAST $XR2 284 
J 0
(-3894 2425);
DISPLAY 0.638298 (-3894 2425);
PAINT MONO (-3894 2425);
FORCEPROP 2 LAST $XR1 292 
J 0
(-3774 2425);
DISPLAY 0.638298 (-3774 2425);
PAINT MONO (-3774 2425);
FORCEPROP 2 LAST $XR0 45 
J 0
(-3654 2425);
DISPLAY 0.638298 (-3654 2425);
PAINT MONO (-3654 2425);
FORCEPROP 1 LAST COMMENT_BODY TRUE
J 0
(-3275 2350);
DISPLAY 0.872340 (-3275 2350);
PAINT GREEN (-3275 2350);
DISPLAY INVISIBLE (-3275 2350);
FORCEPROP 1 LAST OFFPAGE TRUE
J 0
(-3050 2300);
DISPLAY 0.872340 (-3050 2300);
PAINT GREEN (-3050 2300);
DISPLAY INVISIBLE (-3050 2300);
FORCEPROP 2 LAST CDS_LIB standard
J 0
(-3375 2425);
DISPLAY INVISIBLE (-3375 2425);
FORCEPROP 2 LAST PATH I51
J 0
(-3650 2475);
DISPLAY 1.021277 (-3650 2475);
DISPLAY INVISIBLE (-3650 2475);
FORCEADD OFFPAGE..5
(-3375 2275);
FORCEPROP 2 LAST $XR2 284 
J 0
(-3869 2275);
DISPLAY 0.638298 (-3869 2275);
PAINT MONO (-3869 2275);
FORCEPROP 2 LAST $XR1 292 
J 0
(-3749 2275);
DISPLAY 0.638298 (-3749 2275);
PAINT MONO (-3749 2275);
FORCEPROP 2 LAST $XR0 45 
J 0
(-3629 2275);
DISPLAY 0.638298 (-3629 2275);
PAINT MONO (-3629 2275);
FORCEPROP 1 LAST COMMENT_BODY TRUE
J 0
(-3275 2200);
DISPLAY 0.872340 (-3275 2200);
PAINT GREEN (-3275 2200);
DISPLAY INVISIBLE (-3275 2200);
FORCEPROP 1 LAST OFFPAGE TRUE
J 0
(-3050 2150);
DISPLAY 0.872340 (-3050 2150);
PAINT GREEN (-3050 2150);
DISPLAY INVISIBLE (-3050 2150);
FORCEPROP 2 LAST CDS_LIB standard
J 0
(-3375 2275);
DISPLAY INVISIBLE (-3375 2275);
FORCEPROP 2 LAST PATH I52
J 0
(-3625 2325);
DISPLAY 1.021277 (-3625 2325);
DISPLAY INVISIBLE (-3625 2325);
FORCEADD OFFPAGE..1
(-3375 2575);
FORCEPROP 2 LAST $XR2 292 
J 0
(-3866 2575);
DISPLAY 0.638298 (-3866 2575);
PAINT MONO (-3866 2575);
FORCEPROP 2 LAST $XR1 284 
J 0
(-3746 2575);
DISPLAY 0.638298 (-3746 2575);
PAINT MONO (-3746 2575);
FORCEPROP 2 LAST $XR0 45 
J 0
(-3626 2575);
DISPLAY 0.638298 (-3626 2575);
PAINT MONO (-3626 2575);
FORCEPROP 1 LAST COMMENT_BODY TRUE
J 0
(-3250 2475);
DISPLAY 0.872340 (-3250 2475);
PAINT GREEN (-3250 2475);
DISPLAY INVISIBLE (-3250 2475);
FORCEPROP 1 LAST OFFPAGE TRUE
J 0
(-3050 2450);
DISPLAY 0.872340 (-3050 2450);
PAINT GREEN (-3050 2450);
DISPLAY INVISIBLE (-3050 2450);
FORCEPROP 2 LAST CDS_LIB standard
J 0
(-3375 2575);
DISPLAY INVISIBLE (-3375 2575);
FORCEPROP 2 LAST PATH I53
J 0
(-3625 2625);
DISPLAY 1.021277 (-3625 2625);
DISPLAY INVISIBLE (-3625 2625);
FORCEADD OFFPAGE..1
(-3375 2875);
FORCEPROP 2 LAST $XR0 222 
J 0
(-3657 2875);
DISPLAY 0.638298 (-3657 2875);
PAINT MONO (-3657 2875);
FORCEPROP 1 LAST COMMENT_BODY TRUE
J 0
(-3250 2775);
DISPLAY 0.872340 (-3250 2775);
PAINT GREEN (-3250 2775);
DISPLAY INVISIBLE (-3250 2775);
FORCEPROP 1 LAST OFFPAGE TRUE
J 0
(-3050 2750);
DISPLAY 0.872340 (-3050 2750);
PAINT GREEN (-3050 2750);
DISPLAY INVISIBLE (-3050 2750);
FORCEPROP 2 LAST CDS_LIB standard
J 0
(-3375 2875);
DISPLAY INVISIBLE (-3375 2875);
FORCEPROP 2 LAST PATH I54
J 0
(-3650 2925);
DISPLAY 1.021277 (-3650 2925);
DISPLAY INVISIBLE (-3650 2925);
FORCEADD OFFPAGE..5
(-3375 3025);
FORCEPROP 2 LAST $XR1 254 
J 0
(-3750 3025);
DISPLAY 0.638298 (-3750 3025);
PAINT MONO (-3750 3025);
FORCEPROP 2 LAST $XR0 214 
J 0
(-3630 3025);
DISPLAY 0.638298 (-3630 3025);
PAINT MONO (-3630 3025);
FORCEPROP 1 LAST COMMENT_BODY TRUE
J 0
(-3275 2950);
DISPLAY 0.872340 (-3275 2950);
PAINT GREEN (-3275 2950);
DISPLAY INVISIBLE (-3275 2950);
FORCEPROP 1 LAST OFFPAGE TRUE
J 0
(-3050 2900);
DISPLAY 0.872340 (-3050 2900);
PAINT GREEN (-3050 2900);
DISPLAY INVISIBLE (-3050 2900);
FORCEPROP 2 LAST CDS_LIB standard
J 0
(-3375 3025);
DISPLAY INVISIBLE (-3375 3025);
FORCEPROP 2 LAST PATH I55
J 0
(-3625 3075);
DISPLAY 1.021277 (-3625 3075);
DISPLAY INVISIBLE (-3625 3075);
FORCEADD Q_RES..1
(-2175 2425);
FORCEPROP 1 LAST PART_NUMBER CS00002JB13
J 0
(-2050 2475);
DISPLAY 0.617021 (-2050 2475);
PAINT BLUE (-2050 2475);
DISPLAY INVISIBLE (-2050 2475);
FORCEPROP 1 LAST PACK_TYPE 0402LF
J 0
(-1925 2425);
DISPLAY 0.617021 (-1925 2425);
PAINT SKYBLUE (-1925 2425);
FORCEPROP 1 LAST WATTAGE 1/16W
J 2
(-1725 2525);
DISPLAY 0.617021 (-1725 2525);
PAINT SKYBLUE (-1725 2525);
FORCEPROP 1 LAST TOLERANCE 5%
J 0
(-2000 2425);
DISPLAY 0.617021 (-2000 2425);
PAINT SKYBLUE (-2000 2425);
FORCEPROP 1 LAST MATERIAL CHIP
J 0
(-2050 2525);
DISPLAY 0.617021 (-2050 2525);
PAINT SKYBLUE (-2050 2525);
FORCEPROP 1 LAST VALUE 0
J 2
(-2025 2425);
DISPLAY 0.617021 (-2025 2425);
PAINT SKYBLUE (-2025 2425);
FORCEPROP 1 LAST LOCATION R311
J 0
(-2425 2425);
DISPLAY 0.617021 (-2425 2425);
PAINT AQUA (-2425 2425);
FORCEPROP 1 LASTPIN (-2275 2425) $PN 1
J 0
(-2263 2437);
DISPLAY 0.617021 (-2263 2437);
PAINT MONO (-2263 2437);
FORCEPROP 1 LASTPIN (-2075 2425) $PN 2
J 0
(-2113 2437);
DISPLAY 0.617021 (-2113 2437);
PAINT MONO (-2113 2437);
FORCEPROP 2 LAST CDS_LIB pure_quanta
J 0
(-2175 2425);
DISPLAY INVISIBLE (-2175 2425);
FORCEPROP 1 LAST PATH I56
J 0
(-2225 2575);
DISPLAY 0.978723 (-2225 2575);
PAINT WHITE (-2225 2575);
DISPLAY INVISIBLE (-2225 2575);
FORCEPROP 1 LAST LOCATION R311
J 0
(-2225 2525);
DISPLAY 1.021277 (-2225 2525);
PAINT AQUA (-2225 2525);
DISPLAY INVISIBLE (-2225 2525);
FORCEPROP 0 LAST $SEC 1
J 0
(-2225 2525);
DISPLAY 0.680851 (-2225 2525);
PAINT MONO (-2225 2525);
DISPLAY INVISIBLE (-2225 2525);
FORCEPROP 0 LAST CDS_SEC 1
J 0
(-2225 2525);
DISPLAY 1.021277 (-2225 2525);
DISPLAY INVISIBLE (-2225 2525);
FORCEADD Q_RES..1
(-2175 2275);
FORCEPROP 1 LAST PART_NUMBER CS00002JB13
J 0
(-2050 2325);
DISPLAY 0.617021 (-2050 2325);
PAINT BLUE (-2050 2325);
DISPLAY INVISIBLE (-2050 2325);
FORCEPROP 1 LAST WATTAGE 1/16W
J 2
(-1725 2375);
DISPLAY 0.617021 (-1725 2375);
PAINT SKYBLUE (-1725 2375);
FORCEPROP 1 LAST MATERIAL CHIP
J 0
(-2050 2375);
DISPLAY 0.617021 (-2050 2375);
PAINT SKYBLUE (-2050 2375);
FORCEPROP 1 LAST VALUE 0
J 2
(-2025 2275);
DISPLAY 0.617021 (-2025 2275);
PAINT SKYBLUE (-2025 2275);
FORCEPROP 1 LAST PACK_TYPE 0402LF
J 0
(-1925 2275);
DISPLAY 0.617021 (-1925 2275);
PAINT SKYBLUE (-1925 2275);
FORCEPROP 1 LAST TOLERANCE 5%
J 0
(-2000 2275);
DISPLAY 0.617021 (-2000 2275);
PAINT SKYBLUE (-2000 2275);
FORCEPROP 1 LAST LOCATION R312
J 0
(-2425 2275);
DISPLAY 0.617021 (-2425 2275);
PAINT AQUA (-2425 2275);
FORCEPROP 1 LASTPIN (-2275 2275) $PN 1
J 0
(-2263 2287);
DISPLAY 0.617021 (-2263 2287);
PAINT MONO (-2263 2287);
FORCEPROP 1 LASTPIN (-2075 2275) $PN 2
J 0
(-2113 2287);
DISPLAY 0.617021 (-2113 2287);
PAINT MONO (-2113 2287);
FORCEPROP 2 LAST CDS_LIB pure_quanta
J 0
(-2175 2275);
DISPLAY INVISIBLE (-2175 2275);
FORCEPROP 1 LAST PATH I57
J 0
(-2225 2425);
DISPLAY 0.978723 (-2225 2425);
PAINT WHITE (-2225 2425);
DISPLAY INVISIBLE (-2225 2425);
FORCEPROP 1 LAST LOCATION R312
J 0
(-2225 2375);
DISPLAY 1.021277 (-2225 2375);
PAINT AQUA (-2225 2375);
DISPLAY INVISIBLE (-2225 2375);
FORCEPROP 0 LAST $SEC 1
J 0
(-2225 2375);
DISPLAY 0.680851 (-2225 2375);
PAINT MONO (-2225 2375);
DISPLAY INVISIBLE (-2225 2375);
FORCEPROP 0 LAST CDS_SEC 1
J 0
(-2225 2375);
DISPLAY 1.021277 (-2225 2375);
DISPLAY INVISIBLE (-2225 2375);
FORCEADD Q_RES..1
(-2175 2575);
FORCEPROP 1 LAST PART_NUMBER CS11502FB07
J 0
(-2050 2625);
DISPLAY 0.617021 (-2050 2625);
PAINT BLUE (-2050 2625);
DISPLAY INVISIBLE (-2050 2625);
FORCEPROP 1 LAST WATTAGE 1/16W
J 2
(-1725 2675);
DISPLAY 0.617021 (-1725 2675);
PAINT SKYBLUE (-1725 2675);
FORCEPROP 1 LAST MATERIAL CHIP
J 0
(-2050 2675);
DISPLAY 0.617021 (-2050 2675);
PAINT SKYBLUE (-2050 2675);
FORCEPROP 1 LAST PACK_TYPE 0402LF
J 0
(-1825 2575);
DISPLAY 0.617021 (-1825 2575);
PAINT SKYBLUE (-1825 2575);
FORCEPROP 1 LAST TOLERANCE 1%
J 0
(-1925 2575);
DISPLAY 0.617021 (-1925 2575);
PAINT SKYBLUE (-1925 2575);
FORCEPROP 1 LAST VALUE 150
J 2
(-1950 2575);
DISPLAY 0.617021 (-1950 2575);
PAINT SKYBLUE (-1950 2575);
FORCEPROP 1 LAST LOCATION R310
J 0
(-2425 2575);
DISPLAY 0.617021 (-2425 2575);
PAINT AQUA (-2425 2575);
FORCEPROP 1 LASTPIN (-2275 2575) $PN 1
J 0
(-2263 2587);
DISPLAY 0.617021 (-2263 2587);
PAINT MONO (-2263 2587);
FORCEPROP 1 LASTPIN (-2075 2575) $PN 2
J 0
(-2113 2587);
DISPLAY 0.617021 (-2113 2587);
PAINT MONO (-2113 2587);
FORCEPROP 2 LAST CDS_LIB pure_quanta
J 0
(-2175 2575);
DISPLAY INVISIBLE (-2175 2575);
FORCEPROP 1 LAST PATH I58
J 0
(-2225 2725);
DISPLAY 0.978723 (-2225 2725);
PAINT WHITE (-2225 2725);
DISPLAY INVISIBLE (-2225 2725);
FORCEPROP 1 LAST LOCATION R310
J 0
(-2025 2650);
DISPLAY 1.021277 (-2025 2650);
PAINT AQUA (-2025 2650);
DISPLAY INVISIBLE (-2025 2650);
FORCEPROP 0 LAST $SEC 1
J 0
(-2025 2650);
DISPLAY 0.680851 (-2025 2650);
PAINT MONO (-2025 2650);
DISPLAY INVISIBLE (-2025 2650);
FORCEPROP 0 LAST CDS_SEC 1
J 0
(-2025 2650);
DISPLAY 1.021277 (-2025 2650);
DISPLAY INVISIBLE (-2025 2650);
FORCEADD Q_RES..1
(-2175 2875);
FORCEPROP 1 LAST PART_NUMBER CS00002JB13
J 0
(-2050 2925);
DISPLAY 0.617021 (-2050 2925);
PAINT BLUE (-2050 2925);
DISPLAY INVISIBLE (-2050 2925);
FORCEPROP 1 LAST MATERIAL CHIP
J 0
(-2050 2975);
DISPLAY 0.617021 (-2050 2975);
PAINT SKYBLUE (-2050 2975);
FORCEPROP 1 LAST VALUE 0
J 2
(-2025 2875);
DISPLAY 0.617021 (-2025 2875);
PAINT SKYBLUE (-2025 2875);
FORCEPROP 1 LAST PACK_TYPE 0402LF
J 0
(-1925 2875);
DISPLAY 0.617021 (-1925 2875);
PAINT SKYBLUE (-1925 2875);
FORCEPROP 1 LAST TOLERANCE 5%
J 0
(-2000 2875);
DISPLAY 0.617021 (-2000 2875);
PAINT SKYBLUE (-2000 2875);
FORCEPROP 1 LAST WATTAGE 1/16W
J 2
(-1750 2975);
DISPLAY 0.617021 (-1750 2975);
PAINT SKYBLUE (-1750 2975);
FORCEPROP 1 LAST LOCATION R309
J 0
(-2425 2875);
DISPLAY 0.617021 (-2425 2875);
PAINT AQUA (-2425 2875);
FORCEPROP 1 LASTPIN (-2275 2875) $PN 1
J 0
(-2263 2887);
DISPLAY 0.617021 (-2263 2887);
PAINT MONO (-2263 2887);
FORCEPROP 1 LASTPIN (-2075 2875) $PN 2
J 0
(-2113 2887);
DISPLAY 0.617021 (-2113 2887);
PAINT MONO (-2113 2887);
FORCEPROP 2 LAST CDS_LIB pure_quanta
J 0
(-2175 2875);
DISPLAY INVISIBLE (-2175 2875);
FORCEPROP 1 LAST PATH I59
J 0
(-2225 3025);
DISPLAY 0.978723 (-2225 3025);
PAINT WHITE (-2225 3025);
DISPLAY INVISIBLE (-2225 3025);
FORCEPROP 1 LAST LOCATION R309
J 0
(-2225 2975);
DISPLAY 1.021277 (-2225 2975);
PAINT AQUA (-2225 2975);
DISPLAY INVISIBLE (-2225 2975);
FORCEPROP 0 LAST $SEC 1
J 0
(-2225 2975);
DISPLAY 0.680851 (-2225 2975);
PAINT MONO (-2225 2975);
DISPLAY INVISIBLE (-2225 2975);
FORCEPROP 0 LAST CDS_SEC 1
J 0
(-2225 2975);
DISPLAY 1.021277 (-2225 2975);
DISPLAY INVISIBLE (-2225 2975);
FORCEADD Q_RES..2
R 2
(-2725 -2300);
FORCEPROP 1 LAST PART_NUMBER CS25232FB08
J 2
(-2765 -2425);
DISPLAY 0.617021 (-2765 -2425);
PAINT BLUE (-2765 -2425);
DISPLAY INVISIBLE (-2765 -2425);
FORCEPROP 1 LAST PACK_TYPE 0402LF
J 2
(-2765 -2475);
DISPLAY 0.617021 (-2765 -2475);
PAINT SKYBLUE (-2765 -2475);
FORCEPROP 1 LAST VALUE 5.23K
J 2
(-2770 -2225);
DISPLAY 0.617021 (-2770 -2225);
PAINT SKYBLUE (-2770 -2225);
FORCEPROP 1 LAST MATERIAL CHIP
J 2
(-2765 -2375);
DISPLAY 0.617021 (-2765 -2375);
PAINT SKYBLUE (-2765 -2375);
FORCEPROP 1 LAST TOLERANCE 1%
J 2
(-2770 -2275);
DISPLAY 0.617021 (-2770 -2275);
PAINT SKYBLUE (-2770 -2275);
FORCEPROP 1 LAST WATTAGE 1/16W
J 2
(-2765 -2325);
DISPLAY 0.617021 (-2765 -2325);
PAINT SKYBLUE (-2765 -2325);
FORCEPROP 1 LAST LOCATION PR318
J 2
(-2770 -2175);
DISPLAY 0.617021 (-2770 -2175);
PAINT AQUA (-2770 -2175);
FORCEPROP 1 LASTPIN (-2725 -2200) $PN 1
J 2
(-2730 -2238);
DISPLAY 0.617021 (-2730 -2238);
PAINT MONO (-2730 -2238);
FORCEPROP 1 LASTPIN (-2725 -2400) $PN 2
J 2
(-2730 -2390);
DISPLAY 0.617021 (-2730 -2390);
PAINT MONO (-2730 -2390);
FORCEPROP 2 LAST CDS_LIB pure_quanta
J 2
(-2725 -2300);
DISPLAY INVISIBLE (-2725 -2300);
FORCEPROP 1 LAST PATH I6
J 2
(-2775 -2125);
DISPLAY 0.978723 (-2775 -2125);
PAINT WHITE (-2775 -2125);
DISPLAY INVISIBLE (-2775 -2125);
FORCEPROP 1 LAST LOCATION PR318
J 2
(-2775 -2125);
DISPLAY 1.021277 (-2775 -2125);
PAINT AQUA (-2775 -2125);
DISPLAY INVISIBLE (-2775 -2125);
FORCEPROP 0 LAST $SEC 1
J 2
(-2775 -2125);
DISPLAY 0.680851 (-2775 -2125);
PAINT MONO (-2775 -2125);
DISPLAY INVISIBLE (-2775 -2125);
FORCEPROP 0 LAST CDS_SEC 1
J 2
(-2775 -2125);
DISPLAY 1.021277 (-2775 -2125);
DISPLAY INVISIBLE (-2775 -2125);
FORCEADD Q_RES..1
(-2175 3025);
FORCEPROP 1 LAST PART_NUMBER CS00002JB13
J 0
(-2050 3075);
DISPLAY 0.617021 (-2050 3075);
PAINT BLUE (-2050 3075);
DISPLAY INVISIBLE (-2050 3075);
FORCEPROP 1 LAST MATERIAL CHIP
J 0
(-2050 3125);
DISPLAY 0.617021 (-2050 3125);
PAINT SKYBLUE (-2050 3125);
FORCEPROP 1 LAST TOLERANCE 5%
J 0
(-2000 3025);
DISPLAY 0.617021 (-2000 3025);
PAINT SKYBLUE (-2000 3025);
FORCEPROP 1 LAST VALUE 0
J 2
(-2025 3025);
DISPLAY 0.617021 (-2025 3025);
PAINT SKYBLUE (-2025 3025);
FORCEPROP 1 LAST PACK_TYPE 0402LF
J 0
(-1925 3025);
DISPLAY 0.617021 (-1925 3025);
PAINT SKYBLUE (-1925 3025);
FORCEPROP 1 LAST WATTAGE 1/16W
J 2
(-1750 3125);
DISPLAY 0.617021 (-1750 3125);
PAINT SKYBLUE (-1750 3125);
FORCEPROP 1 LAST LOCATION R308
J 0
(-2425 3025);
DISPLAY 0.617021 (-2425 3025);
PAINT AQUA (-2425 3025);
FORCEPROP 1 LASTPIN (-2275 3025) $PN 1
J 0
(-2263 3037);
DISPLAY 0.617021 (-2263 3037);
PAINT MONO (-2263 3037);
FORCEPROP 1 LASTPIN (-2075 3025) $PN 2
J 0
(-2113 3037);
DISPLAY 0.617021 (-2113 3037);
PAINT MONO (-2113 3037);
FORCEPROP 2 LAST CDS_LIB pure_quanta
J 0
(-2175 3025);
DISPLAY INVISIBLE (-2175 3025);
FORCEPROP 1 LAST PATH I60
J 0
(-2225 3175);
DISPLAY 0.978723 (-2225 3175);
PAINT WHITE (-2225 3175);
DISPLAY INVISIBLE (-2225 3175);
FORCEPROP 1 LAST LOCATION R308
J 0
(-2225 3125);
DISPLAY 1.021277 (-2225 3125);
PAINT AQUA (-2225 3125);
DISPLAY INVISIBLE (-2225 3125);
FORCEPROP 0 LAST $SEC 1
J 0
(-2225 3125);
DISPLAY 0.680851 (-2225 3125);
PAINT MONO (-2225 3125);
DISPLAY INVISIBLE (-2225 3125);
FORCEPROP 0 LAST CDS_SEC 1
J 0
(-2225 3125);
DISPLAY 1.021277 (-2225 3125);
DISPLAY INVISIBLE (-2225 3125);
FORCEADD Q_RES..1
(-2175 3175);
FORCEPROP 1 LAST PART_NUMBER CS21002FB06
J 0
(-2050 3225);
DISPLAY 0.617021 (-2050 3225);
PAINT BLUE (-2050 3225);
DISPLAY INVISIBLE (-2050 3225);
FORCEPROP 1 LAST WATTAGE 1/16W
J 2
(-1750 3275);
DISPLAY 0.617021 (-1750 3275);
PAINT SKYBLUE (-1750 3275);
FORCEPROP 1 LAST VALUE 1K
J 2
(-2000 3175);
DISPLAY 0.617021 (-2000 3175);
PAINT SKYBLUE (-2000 3175);
FORCEPROP 1 LAST TOLERANCE 1%
J 0
(-1975 3175);
DISPLAY 0.617021 (-1975 3175);
PAINT SKYBLUE (-1975 3175);
FORCEPROP 1 LAST PACK_TYPE 0402LF
J 0
(-1875 3175);
DISPLAY 0.617021 (-1875 3175);
PAINT SKYBLUE (-1875 3175);
FORCEPROP 1 LAST MATERIAL CHIP
J 0
(-2050 3275);
DISPLAY 0.617021 (-2050 3275);
PAINT SKYBLUE (-2050 3275);
FORCEPROP 1 LAST LOCATION R307
J 0
(-2425 3175);
DISPLAY 0.617021 (-2425 3175);
PAINT AQUA (-2425 3175);
FORCEPROP 1 LASTPIN (-2275 3175) $PN 1
J 0
(-2263 3187);
DISPLAY 0.617021 (-2263 3187);
PAINT MONO (-2263 3187);
FORCEPROP 1 LASTPIN (-2075 3175) $PN 2
J 0
(-2113 3187);
DISPLAY 0.617021 (-2113 3187);
PAINT MONO (-2113 3187);
FORCEPROP 2 LAST CDS_LIB pure_quanta
J 0
(-2175 3175);
DISPLAY INVISIBLE (-2175 3175);
FORCEPROP 1 LAST PATH I61
J 0
(-2225 3325);
DISPLAY 0.978723 (-2225 3325);
PAINT WHITE (-2225 3325);
DISPLAY INVISIBLE (-2225 3325);
FORCEPROP 1 LAST LOCATION R307
J 0
(-2225 3275);
DISPLAY 1.021277 (-2225 3275);
PAINT AQUA (-2225 3275);
DISPLAY INVISIBLE (-2225 3275);
FORCEPROP 0 LAST $SEC 1
J 0
(-2225 3275);
DISPLAY 0.680851 (-2225 3275);
PAINT MONO (-2225 3275);
DISPLAY INVISIBLE (-2225 3275);
FORCEPROP 0 LAST CDS_SEC 1
J 0
(-2225 3275);
DISPLAY 1.021277 (-2225 3275);
DISPLAY INVISIBLE (-2225 3275);
FORCEADD VCC15..1
(-2600 3275);
FORCEPROP 3 LASTPIN (-2600 3225) SIG_NAME P3V3_AUX\g
J 0
(-2590 3235);
DISPLAY 0.659574 (-2590 3235);
PAINT MONO (-2590 3235);
DISPLAY INVISIBLE (-2590 3235);
FORCEPROP 1 LAST HDL_POWER P3V3_AUX
J 1
(-2600 3325);
DISPLAY 0.617021 (-2600 3325);
PAINT GREEN (-2600 3325);
FORCEPROP 2 LAST CDS_LIB logical_power
J 0
(-2600 3275);
PAINT MONO (-2600 3275);
DISPLAY INVISIBLE (-2600 3275);
FORCEPROP 1 LAST PATH I62
J 0
(-2550 3300);
DISPLAY 0.872340 (-2550 3300);
PAINT AQUA (-2550 3300);
DISPLAY INVISIBLE (-2550 3300);
FORCEADD Q_RES..1
(-1825 1025);
FORCEPROP 1 LAST PART_NUMBER CS00002JB13
J 0
(-1700 1075);
DISPLAY 0.617021 (-1700 1075);
PAINT BLUE (-1700 1075);
DISPLAY INVISIBLE (-1700 1075);
FORCEPROP 1 LAST WATTAGE 1/16W
J 2
(-1400 1125);
DISPLAY 0.617021 (-1400 1125);
PAINT SKYBLUE (-1400 1125);
FORCEPROP 1 LAST MATERIAL CHIP
J 0
(-1700 1125);
DISPLAY 0.617021 (-1700 1125);
PAINT SKYBLUE (-1700 1125);
FORCEPROP 1 LAST PACK_TYPE 0402LF
J 0
(-1575 1025);
DISPLAY 0.617021 (-1575 1025);
PAINT SKYBLUE (-1575 1025);
FORCEPROP 1 LAST TOLERANCE 5%
J 0
(-1650 1025);
DISPLAY 0.617021 (-1650 1025);
PAINT SKYBLUE (-1650 1025);
FORCEPROP 1 LAST VALUE 0
J 2
(-1675 1025);
DISPLAY 0.617021 (-1675 1025);
PAINT SKYBLUE (-1675 1025);
FORCEPROP 1 LAST LOCATION PR317
J 0
(-2050 1025);
DISPLAY 0.617021 (-2050 1025);
PAINT AQUA (-2050 1025);
FORCEPROP 1 LASTPIN (-1925 1025) $PN 1
J 0
(-1913 1037);
DISPLAY 0.617021 (-1913 1037);
PAINT MONO (-1913 1037);
FORCEPROP 1 LASTPIN (-1725 1025) $PN 2
J 0
(-1763 1037);
DISPLAY 0.617021 (-1763 1037);
PAINT MONO (-1763 1037);
FORCEPROP 2 LAST CDS_LIB pure_quanta
J 0
(-1825 1025);
DISPLAY INVISIBLE (-1825 1025);
FORCEPROP 1 LAST PATH I63
J 0
(-1875 1175);
DISPLAY 0.978723 (-1875 1175);
PAINT WHITE (-1875 1175);
DISPLAY INVISIBLE (-1875 1175);
FORCEPROP 1 LAST LOCATION PR317
J 0
(-1875 1125);
DISPLAY 1.021277 (-1875 1125);
PAINT AQUA (-1875 1125);
DISPLAY INVISIBLE (-1875 1125);
FORCEPROP 0 LAST $SEC 1
J 0
(-1875 1125);
DISPLAY 0.680851 (-1875 1125);
PAINT MONO (-1875 1125);
DISPLAY INVISIBLE (-1875 1125);
FORCEPROP 0 LAST CDS_SEC 1
J 0
(-1875 1125);
DISPLAY 1.021277 (-1875 1125);
DISPLAY INVISIBLE (-1875 1125);
FORCEADD Q_CAP..1
(-1375 850);
FORCEPROP 1 LAST PART_NUMBER TMP_QCH2336K1B12
J 0
(-1325 675);
DISPLAY 0.617021 (-1325 675);
PAINT BLUE (-1325 675);
DISPLAY INVISIBLE (-1325 675);
FORCEPROP 1 LAST MATERIAL X7R
J 0
(-1325 775);
DISPLAY 0.617021 (-1325 775);
PAINT SKYBLUE (-1325 775);
FORCEPROP 1 LAST TOLERANCE 10%
J 0
(-1325 825);
DISPLAY 0.617021 (-1325 825);
PAINT SKYBLUE (-1325 825);
FORCEPROP 1 LAST PACK_TYPE 0402
J 0
(-1325 725);
DISPLAY 0.617021 (-1325 725);
PAINT SKYBLUE (-1325 725);
FORCEPROP 1 LAST VALUE 3300PF
J 0
(-1325 925);
DISPLAY 0.617021 (-1325 925);
PAINT SKYBLUE (-1325 925);
FORCEPROP 1 LAST VOLTAGE 50V
J 0
(-1325 875);
DISPLAY 0.617021 (-1325 875);
PAINT SKYBLUE (-1325 875);
FORCEPROP 1 LAST LOCATION PC549
J 0
(-1325 975);
DISPLAY 0.617021 (-1325 975);
PAINT AQUA (-1325 975);
FORCEPROP 1 LASTPIN (-1375 950) $PN 1
J 0
(-1365 930);
DISPLAY 0.617021 (-1365 930);
PAINT MONO (-1365 930);
FORCEPROP 1 LASTPIN (-1375 750) $PN 2
J 0
(-1365 730);
DISPLAY 0.617021 (-1365 730);
PAINT MONO (-1365 730);
FORCEPROP 2 LAST CDS_LIB pure_quanta
J 0
(-1375 850);
DISPLAY INVISIBLE (-1375 850);
FORCEPROP 1 LAST PATH I64
J 0
(-1325 1000);
DISPLAY 0.978723 (-1325 1000);
PAINT WHITE (-1325 1000);
DISPLAY INVISIBLE (-1325 1000);
FORCEPROP 1 LAST LOCATION PC549
J 0
(-1325 975);
DISPLAY 1.021277 (-1325 975);
PAINT AQUA (-1325 975);
DISPLAY INVISIBLE (-1325 975);
FORCEPROP 0 LAST $SEC 1
J 0
(-1325 975);
DISPLAY 0.680851 (-1325 975);
PAINT MONO (-1325 975);
DISPLAY INVISIBLE (-1325 975);
FORCEPROP 0 LAST CDS_SEC 1
J 0
(-1325 975);
DISPLAY 1.021277 (-1325 975);
DISPLAY INVISIBLE (-1325 975);
FORCEADD Q_RES..1
(-1850 1875);
FORCEPROP 1 LAST PART_NUMBER CS00002JB13
J 0
(-1725 1925);
DISPLAY 0.617021 (-1725 1925);
PAINT BLUE (-1725 1925);
DISPLAY INVISIBLE (-1725 1925);
FORCEPROP 1 LAST MATERIAL CHIP
J 0
(-1725 1975);
DISPLAY 0.617021 (-1725 1975);
PAINT SKYBLUE (-1725 1975);
FORCEPROP 1 LAST WATTAGE 1/16W
J 2
(-1425 1975);
DISPLAY 0.617021 (-1425 1975);
PAINT SKYBLUE (-1425 1975);
FORCEPROP 1 LAST VALUE 0
J 2
(-1700 1875);
DISPLAY 0.617021 (-1700 1875);
PAINT SKYBLUE (-1700 1875);
FORCEPROP 1 LAST TOLERANCE 5%
J 0
(-1675 1875);
DISPLAY 0.617021 (-1675 1875);
PAINT SKYBLUE (-1675 1875);
FORCEPROP 1 LAST PACK_TYPE 0402LF
J 0
(-1600 1875);
DISPLAY 0.617021 (-1600 1875);
PAINT SKYBLUE (-1600 1875);
FORCEPROP 1 LAST LOCATION R2520
J 0
(-2100 1875);
DISPLAY 0.617021 (-2100 1875);
PAINT AQUA (-2100 1875);
FORCEPROP 1 LASTPIN (-1950 1875) $PN 1
J 0
(-1938 1887);
DISPLAY 0.617021 (-1938 1887);
PAINT MONO (-1938 1887);
FORCEPROP 1 LASTPIN (-1750 1875) $PN 2
J 0
(-1788 1887);
DISPLAY 0.617021 (-1788 1887);
PAINT MONO (-1788 1887);
FORCEPROP 2 LAST CDS_LIB pure_quanta
J 0
(-1850 1875);
DISPLAY INVISIBLE (-1850 1875);
FORCEPROP 1 LAST PATH I65
J 0
(-1900 2025);
DISPLAY 0.978723 (-1900 2025);
PAINT WHITE (-1900 2025);
DISPLAY INVISIBLE (-1900 2025);
FORCEPROP 1 LAST LOCATION R2520
J 0
(-1900 1975);
DISPLAY 1.021277 (-1900 1975);
PAINT AQUA (-1900 1975);
DISPLAY INVISIBLE (-1900 1975);
FORCEPROP 0 LAST $SEC 1
J 0
(-1900 1975);
DISPLAY 0.680851 (-1900 1975);
PAINT MONO (-1900 1975);
DISPLAY INVISIBLE (-1900 1975);
FORCEPROP 0 LAST CDS_SEC 1
J 0
(-1900 1975);
DISPLAY 1.021277 (-1900 1975);
DISPLAY INVISIBLE (-1900 1975);
FORCEADD Q_RES..1
(-1850 1725);
FORCEPROP 1 LAST PART_NUMBER CS00002JB13
J 0
(-1725 1775);
DISPLAY 0.617021 (-1725 1775);
PAINT BLUE (-1725 1775);
DISPLAY INVISIBLE (-1725 1775);
FORCEPROP 1 LAST PACK_TYPE 0402LF
J 0
(-1600 1725);
DISPLAY 0.617021 (-1600 1725);
PAINT SKYBLUE (-1600 1725);
FORCEPROP 1 LAST WATTAGE 1/16W
J 2
(-1425 1825);
DISPLAY 0.617021 (-1425 1825);
PAINT SKYBLUE (-1425 1825);
FORCEPROP 1 LAST MATERIAL CHIP
J 0
(-1725 1825);
DISPLAY 0.617021 (-1725 1825);
PAINT SKYBLUE (-1725 1825);
FORCEPROP 1 LAST TOLERANCE 5%
J 0
(-1675 1725);
DISPLAY 0.617021 (-1675 1725);
PAINT SKYBLUE (-1675 1725);
FORCEPROP 1 LAST VALUE 0
J 2
(-1700 1725);
DISPLAY 0.617021 (-1700 1725);
PAINT SKYBLUE (-1700 1725);
FORCEPROP 1 LAST LOCATION R2521
J 0
(-2100 1725);
DISPLAY 0.617021 (-2100 1725);
PAINT AQUA (-2100 1725);
FORCEPROP 1 LASTPIN (-1950 1725) $PN 1
J 0
(-1938 1737);
DISPLAY 0.617021 (-1938 1737);
PAINT MONO (-1938 1737);
FORCEPROP 1 LASTPIN (-1750 1725) $PN 2
J 0
(-1788 1737);
DISPLAY 0.617021 (-1788 1737);
PAINT MONO (-1788 1737);
FORCEPROP 2 LAST CDS_LIB pure_quanta
J 0
(-1850 1725);
DISPLAY INVISIBLE (-1850 1725);
FORCEPROP 1 LAST PATH I66
J 0
(-1900 1875);
DISPLAY 0.978723 (-1900 1875);
PAINT WHITE (-1900 1875);
DISPLAY INVISIBLE (-1900 1875);
FORCEPROP 1 LAST LOCATION R2521
J 0
(-1900 1825);
DISPLAY 1.021277 (-1900 1825);
PAINT AQUA (-1900 1825);
DISPLAY INVISIBLE (-1900 1825);
FORCEPROP 0 LAST $SEC 1
J 0
(-1900 1825);
DISPLAY 0.680851 (-1900 1825);
PAINT MONO (-1900 1825);
DISPLAY INVISIBLE (-1900 1825);
FORCEPROP 0 LAST CDS_SEC 1
J 0
(-1900 1825);
DISPLAY 1.021277 (-1900 1825);
DISPLAY INVISIBLE (-1900 1825);
FORCEADD Q_CAP..2
(-1350 2750);
FORCEPROP 1 LAST PART_NUMBER TMP_QCH21006JB10
J 1
(-1075 2700);
DISPLAY 0.617021 (-1075 2700);
PAINT BLUE (-1075 2700);
DISPLAY INVISIBLE (-1075 2700);
FORCEPROP 1 LAST TOLERANCE 5%
J 2
(-700 2700);
DISPLAY 0.617021 (-700 2700);
PAINT SKYBLUE (-700 2700);
FORCEPROP 1 LAST MATERIAL X7R
J 0
(-875 2750);
DISPLAY 0.617021 (-875 2750);
PAINT SKYBLUE (-875 2750);
FORCEPROP 1 LAST VOLTAGE 50V
J 0
(-1000 2750);
DISPLAY 0.617021 (-1000 2750);
PAINT SKYBLUE (-1000 2750);
FORCEPROP 1 LAST VALUE 1000PF
J 2
(-1025 2750);
DISPLAY 0.617021 (-1025 2750);
PAINT SKYBLUE (-1025 2750);
FORCEPROP 1 LAST PACK_TYPE 0402
J 1
(-800 2675);
DISPLAY 0.617021 (-800 2675);
PAINT SKYBLUE (-800 2675);
FORCEPROP 1 LAST LOCATION C2860
J 1
(-1550 2750);
DISPLAY 0.617021 (-1550 2750);
PAINT AQUA (-1550 2750);
FORCEPROP 1 LASTPIN (-1450 2750) $PN 1
J 0
(-1460 2765);
DISPLAY 0.617021 (-1460 2765);
PAINT MONO (-1460 2765);
FORCEPROP 1 LASTPIN (-1250 2750) $PN 2
J 0
(-1265 2765);
DISPLAY 0.617021 (-1265 2765);
PAINT MONO (-1265 2765);
FORCEPROP 2 LAST CDS_LIB pure_quanta
J 0
(-1350 2750);
DISPLAY INVISIBLE (-1350 2750);
FORCEPROP 1 LAST PATH I67
J 0
(-1350 2950);
DISPLAY 0.978723 (-1350 2950);
PAINT WHITE (-1350 2950);
DISPLAY INVISIBLE (-1350 2950);
FORCEPROP 1 LAST LOCATION C2860
J 0
(-1400 2850);
DISPLAY 1.021277 (-1400 2850);
PAINT AQUA (-1400 2850);
DISPLAY INVISIBLE (-1400 2850);
FORCEPROP 0 LAST $SEC 1
J 0
(-1400 2850);
DISPLAY 0.680851 (-1400 2850);
PAINT MONO (-1400 2850);
DISPLAY INVISIBLE (-1400 2850);
FORCEPROP 0 LAST CDS_SEC 1
J 0
(-1400 2850);
DISPLAY 1.021277 (-1400 2850);
DISPLAY INVISIBLE (-1400 2850);
FORCEADD Q_CAP..2
(-1325 3175);
FORCEPROP 1 LAST PART_NUMBER TMP_QCH21006JB10
J 1
(-1050 3125);
DISPLAY 0.617021 (-1050 3125);
PAINT BLUE (-1050 3125);
DISPLAY INVISIBLE (-1050 3125);
FORCEPROP 1 LAST MATERIAL EMPTY
J 0
(-850 3175);
DISPLAY 0.617021 (-850 3175);
PAINT RED (-850 3175);
FORCEPROP 1 LAST VOLTAGE 50V
J 0
(-975 3175);
DISPLAY 0.617021 (-975 3175);
PAINT SKYBLUE (-975 3175);
FORCEPROP 1 LAST VALUE 1000PF
J 2
(-1000 3175);
DISPLAY 0.617021 (-1000 3175);
PAINT SKYBLUE (-1000 3175);
FORCEPROP 1 LAST PACK_TYPE 0402
J 1
(-800 3100);
DISPLAY 0.617021 (-800 3100);
PAINT SKYBLUE (-800 3100);
FORCEPROP 1 LAST TOLERANCE 5%
J 2
(-675 3125);
DISPLAY 0.617021 (-675 3125);
PAINT SKYBLUE (-675 3125);
FORCEPROP 1 LAST LOCATION C2859
J 1
(-1525 3175);
DISPLAY 0.617021 (-1525 3175);
PAINT AQUA (-1525 3175);
FORCEPROP 1 LASTPIN (-1425 3175) $PN 1
J 0
(-1435 3190);
DISPLAY 0.617021 (-1435 3190);
PAINT MONO (-1435 3190);
FORCEPROP 1 LASTPIN (-1225 3175) $PN 2
J 0
(-1240 3190);
DISPLAY 0.617021 (-1240 3190);
PAINT MONO (-1240 3190);
FORCEPROP 2 LAST CDS_LIB pure_quanta
J 0
(-1325 3175);
DISPLAY INVISIBLE (-1325 3175);
FORCEPROP 1 LAST PATH I68
J 0
(-1325 3375);
DISPLAY 0.978723 (-1325 3375);
PAINT WHITE (-1325 3375);
DISPLAY INVISIBLE (-1325 3375);
FORCEPROP 1 LAST LOCATION C2859
J 0
(-1375 3275);
DISPLAY 1.021277 (-1375 3275);
PAINT AQUA (-1375 3275);
DISPLAY INVISIBLE (-1375 3275);
FORCEPROP 0 LAST $SEC 1
J 0
(-1375 3275);
DISPLAY 0.680851 (-1375 3275);
PAINT MONO (-1375 3275);
DISPLAY INVISIBLE (-1375 3275);
FORCEPROP 0 LAST CDS_SEC 1
J 0
(-1375 3275);
DISPLAY 1.021277 (-1375 3275);
DISPLAY INVISIBLE (-1375 3275);
FORCEADD UNIVERSAL_GND..1
R 1
(-625 2750);
FORCEPROP 3 LASTPIN (-675 2750) SIG_NAME GND\g
J 0
(-665 2760);
DISPLAY 0.659574 (-665 2760);
PAINT MONO (-665 2760);
DISPLAY INVISIBLE (-665 2760);
FORCEPROP 1 LAST HDL_POWER GND
R 1
J 1
(-550 2775);
DISPLAY 0.872340 (-550 2775);
PAINT GREEN (-550 2775);
DISPLAY INVISIBLE (-550 2775);
FORCEPROP 2 LAST CDS_LIB logical_power
J 0
(-625 2750);
PAINT MONO (-625 2750);
DISPLAY INVISIBLE (-625 2750);
FORCEPROP 1 LAST PATH I69
R 1
J 0
(-625 2825);
DISPLAY 0.872340 (-625 2825);
PAINT AQUA (-625 2825);
DISPLAY INVISIBLE (-625 2825);
FORCEADD Q_RES..1
(-2250 -2425);
FORCEPROP 1 LAST PART_NUMBER CS00002JB13
J 0
(-2125 -2475);
DISPLAY 0.617021 (-2125 -2475);
PAINT BLUE (-2125 -2475);
DISPLAY INVISIBLE (-2125 -2475);
FORCEPROP 1 LAST VALUE 0
J 2
(-2100 -2425);
DISPLAY 0.617021 (-2100 -2425);
PAINT SKYBLUE (-2100 -2425);
FORCEPROP 1 LAST TOLERANCE 5%
J 0
(-2075 -2425);
DISPLAY 0.617021 (-2075 -2425);
PAINT SKYBLUE (-2075 -2425);
FORCEPROP 1 LAST WATTAGE 1/16W
J 2
(-1825 -2525);
DISPLAY 0.617021 (-1825 -2525);
PAINT SKYBLUE (-1825 -2525);
FORCEPROP 1 LAST MATERIAL CHIP
J 0
(-2125 -2525);
DISPLAY 0.617021 (-2125 -2525);
PAINT SKYBLUE (-2125 -2525);
FORCEPROP 1 LAST PACK_TYPE 0402LF
J 0
(-2000 -2425);
DISPLAY 0.617021 (-2000 -2425);
PAINT SKYBLUE (-2000 -2425);
FORCEPROP 1 LAST LOCATION PR303
J 0
(-2475 -2425);
DISPLAY 0.617021 (-2475 -2425);
PAINT AQUA (-2475 -2425);
FORCEPROP 1 LASTPIN (-2350 -2425) $PN 1
J 0
(-2338 -2413);
DISPLAY 0.617021 (-2338 -2413);
PAINT MONO (-2338 -2413);
FORCEPROP 1 LASTPIN (-2150 -2425) $PN 2
J 0
(-2188 -2413);
DISPLAY 0.617021 (-2188 -2413);
PAINT MONO (-2188 -2413);
FORCEPROP 2 LAST CDS_LIB pure_quanta
J 0
(-2250 -2425);
DISPLAY INVISIBLE (-2250 -2425);
FORCEPROP 1 LAST PATH I7
J 0
(-2300 -2275);
DISPLAY 0.978723 (-2300 -2275);
PAINT WHITE (-2300 -2275);
DISPLAY INVISIBLE (-2300 -2275);
FORCEPROP 1 LAST LOCATION PR303
J 0
(-2300 -2325);
DISPLAY 1.021277 (-2300 -2325);
PAINT AQUA (-2300 -2325);
DISPLAY INVISIBLE (-2300 -2325);
FORCEPROP 0 LAST $SEC 1
J 0
(-2300 -2325);
DISPLAY 0.680851 (-2300 -2325);
PAINT MONO (-2300 -2325);
DISPLAY INVISIBLE (-2300 -2325);
FORCEPROP 0 LAST CDS_SEC 1
J 0
(-2300 -2325);
DISPLAY 1.021277 (-2300 -2325);
DISPLAY INVISIBLE (-2300 -2325);
FORCEADD UNIVERSAL_GND..1
R 1
(-625 3175);
FORCEPROP 3 LASTPIN (-675 3175) SIG_NAME GND\g
J 0
(-665 3185);
DISPLAY 0.659574 (-665 3185);
PAINT MONO (-665 3185);
DISPLAY INVISIBLE (-665 3185);
FORCEPROP 1 LAST HDL_POWER GND
R 1
J 1
(-550 3200);
DISPLAY 0.872340 (-550 3200);
PAINT GREEN (-550 3200);
DISPLAY INVISIBLE (-550 3200);
FORCEPROP 2 LAST CDS_LIB logical_power
J 0
(-625 3175);
PAINT MONO (-625 3175);
DISPLAY INVISIBLE (-625 3175);
FORCEPROP 1 LAST PATH I70
R 1
J 0
(-625 3250);
DISPLAY 0.872340 (-625 3250);
PAINT AQUA (-625 3250);
DISPLAY INVISIBLE (-625 3250);
FORCEADD UNIVERSAL_GND..1
(1200 -2600);
FORCEPROP 3 LASTPIN (1200 -2550) SIG_NAME GND\g
J 0
(1210 -2540);
DISPLAY 0.659574 (1210 -2540);
PAINT MONO (1210 -2540);
DISPLAY INVISIBLE (1210 -2540);
FORCEPROP 1 LAST HDL_POWER GND
J 1
(1225 -2675);
DISPLAY 0.872340 (1225 -2675);
PAINT GREEN (1225 -2675);
DISPLAY INVISIBLE (1225 -2675);
FORCEPROP 2 LAST CDS_LIB logical_power
J 0
(1200 -2600);
PAINT MONO (1200 -2600);
DISPLAY INVISIBLE (1200 -2600);
FORCEPROP 1 LAST PATH I71
J 0
(1275 -2600);
DISPLAY 0.872340 (1275 -2600);
PAINT AQUA (1275 -2600);
DISPLAY INVISIBLE (1275 -2600);
FORCEADD Q_CAP..1
(1200 -2375);
FORCEPROP 1 LAST PART_NUMBER TMP_QCH14706KB18
J 0
(1250 -2575);
DISPLAY 0.617021 (1250 -2575);
PAINT BLUE (1250 -2575);
DISPLAY INVISIBLE (1250 -2575);
FORCEPROP 1 LAST TOLERANCE 10%
J 0
(1250 -2425);
DISPLAY 0.617021 (1250 -2425);
PAINT SKYBLUE (1250 -2425);
FORCEPROP 1 LAST VALUE 470PF
J 0
(1250 -2325);
DISPLAY 0.617021 (1250 -2325);
PAINT SKYBLUE (1250 -2325);
FORCEPROP 1 LAST VOLTAGE 50V
J 0
(1250 -2375);
DISPLAY 0.617021 (1250 -2375);
PAINT SKYBLUE (1250 -2375);
FORCEPROP 1 LAST PACK_TYPE 0402
J 0
(1250 -2525);
DISPLAY 0.617021 (1250 -2525);
PAINT SKYBLUE (1250 -2525);
FORCEPROP 1 LAST MATERIAL X7R
J 0
(1250 -2475);
DISPLAY 0.617021 (1250 -2475);
PAINT SKYBLUE (1250 -2475);
FORCEPROP 1 LAST LOCATION PC554
J 0
(1250 -2275);
DISPLAY 0.617021 (1250 -2275);
PAINT AQUA (1250 -2275);
FORCEPROP 1 LASTPIN (1200 -2275) $PN 1
J 0
(1210 -2295);
DISPLAY 0.617021 (1210 -2295);
PAINT MONO (1210 -2295);
FORCEPROP 1 LASTPIN (1200 -2475) $PN 2
J 0
(1210 -2495);
DISPLAY 0.617021 (1210 -2495);
PAINT MONO (1210 -2495);
FORCEPROP 2 LAST CDS_LIB pure_quanta
J 0
(1200 -2375);
DISPLAY INVISIBLE (1200 -2375);
FORCEPROP 1 LAST PATH I72
J 0
(1250 -2225);
DISPLAY 0.978723 (1250 -2225);
PAINT WHITE (1250 -2225);
DISPLAY INVISIBLE (1250 -2225);
FORCEPROP 1 LAST LOCATION PC554
J 0
(1250 -2225);
DISPLAY 1.021277 (1250 -2225);
PAINT AQUA (1250 -2225);
DISPLAY INVISIBLE (1250 -2225);
FORCEPROP 0 LAST $SEC 1
J 0
(1250 -2225);
DISPLAY 0.680851 (1250 -2225);
PAINT MONO (1250 -2225);
DISPLAY INVISIBLE (1250 -2225);
FORCEPROP 0 LAST CDS_SEC 1
J 0
(1250 -2225);
DISPLAY 1.021277 (1250 -2225);
DISPLAY INVISIBLE (1250 -2225);
FORCEADD UNIVERSAL_GND..1
(1850 -2625);
FORCEPROP 3 LASTPIN (1850 -2575) SIG_NAME GND\g
J 0
(1860 -2565);
DISPLAY 0.659574 (1860 -2565);
PAINT MONO (1860 -2565);
DISPLAY INVISIBLE (1860 -2565);
FORCEPROP 1 LAST HDL_POWER GND
J 1
(1875 -2700);
DISPLAY 0.872340 (1875 -2700);
PAINT GREEN (1875 -2700);
DISPLAY INVISIBLE (1875 -2700);
FORCEPROP 2 LAST CDS_LIB logical_power
J 0
(1850 -2625);
DISPLAY INVISIBLE (1850 -2625);
FORCEPROP 1 LAST PATH I73
J 0
(1925 -2625);
DISPLAY 0.872340 (1925 -2625);
PAINT AQUA (1925 -2625);
DISPLAY INVISIBLE (1925 -2625);
FORCEADD Q_RES..2
(1850 -2375);
FORCEPROP 1 LAST PART_NUMBER CS31002FB08
J 0
(1890 -2500);
DISPLAY 0.617021 (1890 -2500);
PAINT BLUE (1890 -2500);
DISPLAY INVISIBLE (1890 -2500);
FORCEPROP 1 LAST WATTAGE 1/16W
J 0
(1890 -2400);
DISPLAY 0.617021 (1890 -2400);
PAINT SKYBLUE (1890 -2400);
FORCEPROP 1 LAST PACK_TYPE 0402LF
J 0
(1890 -2550);
DISPLAY 0.617021 (1890 -2550);
PAINT SKYBLUE (1890 -2550);
FORCEPROP 1 LAST TOLERANCE 1%
J 0
(1895 -2350);
DISPLAY 0.617021 (1895 -2350);
PAINT SKYBLUE (1895 -2350);
FORCEPROP 1 LAST VALUE 10K
J 0
(1895 -2300);
DISPLAY 0.617021 (1895 -2300);
PAINT SKYBLUE (1895 -2300);
FORCEPROP 1 LAST MATERIAL EMPTY
J 0
(1890 -2450);
DISPLAY 0.617021 (1890 -2450);
PAINT RED (1890 -2450);
FORCEPROP 1 LAST LOCATION PR637
J 0
(1895 -2250);
DISPLAY 0.617021 (1895 -2250);
PAINT AQUA (1895 -2250);
FORCEPROP 2 LAST CDS_LIB pure_quanta
J 0
(1850 -2375);
DISPLAY INVISIBLE (1850 -2375);
FORCEPROP 1 LAST PATH I74
J 0
(1900 -2200);
DISPLAY 0.978723 (1900 -2200);
PAINT WHITE (1900 -2200);
DISPLAY INVISIBLE (1900 -2200);
FORCEPROP 0 LAST $SEC 1
J 0
(1900 -2200);
DISPLAY INVISIBLE (1900 -2200);
FORCEPROP 0 LAST CDS_SEC 1
J 0
(1900 -2200);
DISPLAY INVISIBLE (1900 -2200);
FORCEPROP 1 LASTPIN (1850 -2275) $PN 1
J 0
(1855 -2313);
DISPLAY 0.787234 (1855 -2313);
PAINT MONO (1855 -2313);
DISPLAY INVISIBLE (1855 -2313);
FORCEPROP 1 LASTPIN (1850 -2475) $PN 2
J 0
(1855 -2465);
DISPLAY 0.787234 (1855 -2465);
PAINT MONO (1855 -2465);
DISPLAY INVISIBLE (1855 -2465);
FORCEADD OFFPAGE..4
(2000 -1375);
FORCEPROP 2 LAST $XR0 289 
J 0
(2186 -1375);
DISPLAY 0.638298 (2186 -1375);
PAINT MONO (2186 -1375);
FORCEPROP 1 LAST COMMENT_BODY TRUE
J 0
(1975 -1475);
DISPLAY 0.872340 (1975 -1475);
PAINT GREEN (1975 -1475);
DISPLAY INVISIBLE (1975 -1475);
FORCEPROP 1 LAST OFFPAGE TRUE
J 0
(2325 -1500);
DISPLAY 0.872340 (2325 -1500);
PAINT GREEN (2325 -1500);
DISPLAY INVISIBLE (2325 -1500);
FORCEPROP 2 LAST CDS_LIB standard
J 0
(2000 -1375);
DISPLAY INVISIBLE (2000 -1375);
FORCEPROP 2 LAST PATH I75
J 0
(2200 -1325);
DISPLAY 1.021277 (2200 -1325);
DISPLAY INVISIBLE (2200 -1325);
FORCEADD OFFPAGE..2
(2000 -1275);
FORCEPROP 2 LAST $XR0 289 
J 0
(2189 -1275);
DISPLAY 0.638298 (2189 -1275);
PAINT MONO (2189 -1275);
FORCEPROP 1 LAST COMMENT_BODY TRUE
J 0
(1955 -1370);
DISPLAY 0.872340 (1955 -1370);
PAINT GREEN (1955 -1370);
DISPLAY INVISIBLE (1955 -1370);
FORCEPROP 1 LAST OFFPAGE TRUE
J 0
(2325 -1400);
DISPLAY 0.872340 (2325 -1400);
PAINT GREEN (2325 -1400);
DISPLAY INVISIBLE (2325 -1400);
FORCEPROP 2 LAST CDS_LIB standard
J 0
(2000 -1275);
DISPLAY INVISIBLE (2000 -1275);
FORCEPROP 2 LAST PATH I76
J 0
(2200 -1225);
DISPLAY 1.021277 (2200 -1225);
DISPLAY INVISIBLE (2200 -1225);
FORCEADD UNIVERSAL_GND..1
(1900 -925);
FORCEPROP 3 LASTPIN (1900 -875) SIG_NAME GND\g
J 0
(1910 -865);
DISPLAY 0.659574 (1910 -865);
PAINT MONO (1910 -865);
DISPLAY INVISIBLE (1910 -865);
FORCEPROP 1 LAST HDL_POWER GND
J 1
(1925 -1000);
DISPLAY 0.872340 (1925 -1000);
PAINT GREEN (1925 -1000);
DISPLAY INVISIBLE (1925 -1000);
FORCEPROP 2 LAST CDS_LIB logical_power
J 0
(1900 -925);
DISPLAY INVISIBLE (1900 -925);
FORCEPROP 1 LAST PATH I77
J 0
(1975 -925);
DISPLAY 0.872340 (1975 -925);
PAINT AQUA (1975 -925);
DISPLAY INVISIBLE (1975 -925);
FORCEADD OFFPAGE..4
(2000 -1075);
FORCEPROP 2 LAST $XR0 289 
J 0
(2186 -1075);
DISPLAY 0.638298 (2186 -1075);
PAINT MONO (2186 -1075);
FORCEPROP 1 LAST COMMENT_BODY TRUE
J 0
(1975 -1175);
DISPLAY 0.872340 (1975 -1175);
PAINT GREEN (1975 -1175);
DISPLAY INVISIBLE (1975 -1175);
FORCEPROP 1 LAST OFFPAGE TRUE
J 0
(2325 -1200);
DISPLAY 0.872340 (2325 -1200);
PAINT GREEN (2325 -1200);
DISPLAY INVISIBLE (2325 -1200);
FORCEPROP 2 LAST CDS_LIB standard
J 0
(2000 -1075);
DISPLAY INVISIBLE (2000 -1075);
FORCEPROP 2 LAST PATH I78
J 0
(2200 -1025);
DISPLAY 1.021277 (2200 -1025);
DISPLAY INVISIBLE (2200 -1025);
FORCEADD OFFPAGE..2
(2000 -975);
FORCEPROP 2 LAST $XR0 289 
J 0
(2189 -975);
DISPLAY 0.638298 (2189 -975);
PAINT MONO (2189 -975);
FORCEPROP 1 LAST COMMENT_BODY TRUE
J 0
(1955 -1070);
DISPLAY 0.872340 (1955 -1070);
PAINT GREEN (1955 -1070);
DISPLAY INVISIBLE (1955 -1070);
FORCEPROP 1 LAST OFFPAGE TRUE
J 0
(2325 -1100);
DISPLAY 0.872340 (2325 -1100);
PAINT GREEN (2325 -1100);
DISPLAY INVISIBLE (2325 -1100);
FORCEPROP 2 LAST CDS_LIB standard
J 0
(2000 -975);
DISPLAY INVISIBLE (2000 -975);
FORCEPROP 2 LAST PATH I79
J 0
(2200 -925);
DISPLAY 1.021277 (2200 -925);
DISPLAY INVISIBLE (2200 -925);
FORCEADD VCC15..1
(-2525 -2200);
FORCEPROP 3 LASTPIN (-2525 -2250) SIG_NAME P12V_AUX\g
J 0
(-2515 -2240);
DISPLAY 0.659574 (-2515 -2240);
PAINT MONO (-2515 -2240);
DISPLAY INVISIBLE (-2515 -2240);
FORCEPROP 1 LAST HDL_POWER P12V_AUX
J 1
(-2525 -2150);
DISPLAY 0.617021 (-2525 -2150);
PAINT GREEN (-2525 -2150);
FORCEPROP 2 LAST CDS_LIB logical_power
J 0
(-2525 -2200);
DISPLAY INVISIBLE (-2525 -2200);
FORCEPROP 1 LAST PATH I8
J 0
(-2475 -2175);
DISPLAY 0.872340 (-2475 -2175);
PAINT AQUA (-2475 -2175);
DISPLAY INVISIBLE (-2475 -2175);
FORCEADD Q_RES..1
(1275 -850);
FORCEPROP 1 LAST PART_NUMBER CS00002JB13
J 0
(1425 -825);
DISPLAY 0.617021 (1425 -825);
PAINT BLUE (1425 -825);
DISPLAY INVISIBLE (1425 -825);
FORCEPROP 1 LAST VALUE 0
J 2
(1425 -850);
DISPLAY 0.617021 (1425 -850);
PAINT SKYBLUE (1425 -850);
FORCEPROP 1 LAST TOLERANCE 5%
J 0
(1450 -850);
DISPLAY 0.617021 (1450 -850);
PAINT SKYBLUE (1450 -850);
FORCEPROP 1 LAST MATERIAL EMPTY
J 0
(1525 -850);
DISPLAY 0.617021 (1525 -850);
PAINT SKYBLUE (1525 -850);
FORCEPROP 1 LAST LOCATION PR4239
J 0
(1025 -850);
DISPLAY 0.723404 (1025 -850);
PAINT AQUA (1025 -850);
FORCEPROP 1 LASTPIN (1175 -850) $PN 1
J 0
(1187 -838);
DISPLAY 0.787234 (1187 -838);
PAINT MONO (1187 -838);
FORCEPROP 1 LASTPIN (1375 -850) $PN 2
J 0
(1337 -838);
DISPLAY 0.787234 (1337 -838);
PAINT MONO (1337 -838);
FORCEPROP 1 LAST PACK_TYPE 0402LF
J 0
(1225 -750);
DISPLAY 0.404255 (1225 -750);
PAINT SKYBLUE (1225 -750);
DISPLAY INVISIBLE (1225 -750);
FORCEPROP 1 LAST WATTAGE 1/16W
J 2
(1450 -775);
DISPLAY 0.404255 (1450 -775);
PAINT SKYBLUE (1450 -775);
DISPLAY INVISIBLE (1450 -775);
FORCEPROP 2 LAST CDS_LIB pure_quanta
J 0
(1275 -850);
DISPLAY INVISIBLE (1275 -850);
FORCEPROP 1 LAST PATH I80
J 0
(1225 -700);
DISPLAY 0.978723 (1225 -700);
PAINT WHITE (1225 -700);
DISPLAY INVISIBLE (1225 -700);
FORCEPROP 0 LAST $SEC 1
J 0
(1400 -750);
DISPLAY 0.680851 (1400 -750);
PAINT MONO (1400 -750);
DISPLAY INVISIBLE (1400 -750);
FORCEPROP 0 LAST CDS_SEC 1
J 0
(1400 -750);
DISPLAY 1.021277 (1400 -750);
DISPLAY INVISIBLE (1400 -750);
FORCEADD Q_RES..1
(1275 -550);
FORCEPROP 1 LAST PART_NUMBER CS00002JB13
J 0
(1425 -525);
DISPLAY 0.617021 (1425 -525);
PAINT BLUE (1425 -525);
DISPLAY INVISIBLE (1425 -525);
FORCEPROP 1 LAST VALUE 0
J 2
(1425 -550);
DISPLAY 0.617021 (1425 -550);
PAINT SKYBLUE (1425 -550);
FORCEPROP 1 LAST TOLERANCE 5%
J 0
(1450 -550);
DISPLAY 0.617021 (1450 -550);
PAINT SKYBLUE (1450 -550);
FORCEPROP 1 LAST MATERIAL EMPTY
J 0
(1525 -550);
DISPLAY 0.617021 (1525 -550);
PAINT SKYBLUE (1525 -550);
FORCEPROP 1 LAST LOCATION PR4238
J 0
(1025 -550);
DISPLAY 0.723404 (1025 -550);
PAINT AQUA (1025 -550);
FORCEPROP 1 LASTPIN (1175 -550) $PN 1
J 0
(1187 -538);
DISPLAY 0.787234 (1187 -538);
PAINT MONO (1187 -538);
FORCEPROP 1 LASTPIN (1375 -550) $PN 2
J 0
(1337 -538);
DISPLAY 0.787234 (1337 -538);
PAINT MONO (1337 -538);
FORCEPROP 1 LAST WATTAGE 1/16W
J 2
(1450 -475);
DISPLAY 0.404255 (1450 -475);
PAINT SKYBLUE (1450 -475);
DISPLAY INVISIBLE (1450 -475);
FORCEPROP 1 LAST PACK_TYPE 0402LF
J 0
(1225 -450);
DISPLAY 0.404255 (1225 -450);
PAINT SKYBLUE (1225 -450);
DISPLAY INVISIBLE (1225 -450);
FORCEPROP 2 LAST CDS_LIB pure_quanta
J 0
(1275 -550);
DISPLAY INVISIBLE (1275 -550);
FORCEPROP 1 LAST PATH I81
J 0
(1225 -400);
DISPLAY 0.978723 (1225 -400);
PAINT WHITE (1225 -400);
DISPLAY INVISIBLE (1225 -400);
FORCEPROP 0 LAST $SEC 1
J 0
(1400 -450);
DISPLAY 0.680851 (1400 -450);
PAINT MONO (1400 -450);
DISPLAY INVISIBLE (1400 -450);
FORCEPROP 0 LAST CDS_SEC 1
J 0
(1400 -450);
DISPLAY 1.021277 (1400 -450);
DISPLAY INVISIBLE (1400 -450);
FORCEADD UNIVERSAL_GND..1
(1900 -625);
FORCEPROP 3 LASTPIN (1900 -575) SIG_NAME GND\g
J 0
(1910 -565);
DISPLAY 0.659574 (1910 -565);
PAINT MONO (1910 -565);
DISPLAY INVISIBLE (1910 -565);
FORCEPROP 1 LAST HDL_POWER GND
J 1
(1925 -700);
DISPLAY 0.872340 (1925 -700);
PAINT GREEN (1925 -700);
DISPLAY INVISIBLE (1925 -700);
FORCEPROP 2 LAST CDS_LIB logical_power
J 0
(1900 -625);
DISPLAY INVISIBLE (1900 -625);
FORCEPROP 1 LAST PATH I82
J 0
(1975 -625);
DISPLAY 0.872340 (1975 -625);
PAINT AQUA (1975 -625);
DISPLAY INVISIBLE (1975 -625);
FORCEADD OFFPAGE..4
(2000 -775);
FORCEPROP 2 LAST $XR0 290 
J 0
(2186 -775);
DISPLAY 0.638298 (2186 -775);
PAINT MONO (2186 -775);
FORCEPROP 1 LAST COMMENT_BODY TRUE
J 0
(1975 -875);
DISPLAY 0.872340 (1975 -875);
PAINT GREEN (1975 -875);
DISPLAY INVISIBLE (1975 -875);
FORCEPROP 1 LAST OFFPAGE TRUE
J 0
(2325 -900);
DISPLAY 0.872340 (2325 -900);
PAINT GREEN (2325 -900);
DISPLAY INVISIBLE (2325 -900);
FORCEPROP 2 LAST CDS_LIB standard
J 0
(2000 -775);
DISPLAY INVISIBLE (2000 -775);
FORCEPROP 2 LAST PATH I83
J 0
(2200 -725);
DISPLAY 1.021277 (2200 -725);
DISPLAY INVISIBLE (2200 -725);
FORCEADD OFFPAGE..2
(2000 -675);
FORCEPROP 2 LAST $XR0 290 
J 0
(2189 -675);
DISPLAY 0.638298 (2189 -675);
PAINT MONO (2189 -675);
FORCEPROP 1 LAST COMMENT_BODY TRUE
J 0
(1955 -770);
DISPLAY 0.872340 (1955 -770);
PAINT GREEN (1955 -770);
DISPLAY INVISIBLE (1955 -770);
FORCEPROP 1 LAST OFFPAGE TRUE
J 0
(2325 -800);
DISPLAY 0.872340 (2325 -800);
PAINT GREEN (2325 -800);
DISPLAY INVISIBLE (2325 -800);
FORCEPROP 2 LAST CDS_LIB standard
J 0
(2000 -675);
DISPLAY INVISIBLE (2000 -675);
FORCEPROP 2 LAST PATH I84
J 0
(2200 -625);
DISPLAY 1.021277 (2200 -625);
DISPLAY INVISIBLE (2200 -625);
FORCEADD OFFPAGE..4
(2000 -475);
FORCEPROP 2 LAST $XR0 290 
J 0
(2186 -475);
DISPLAY 0.638298 (2186 -475);
PAINT MONO (2186 -475);
FORCEPROP 1 LAST COMMENT_BODY TRUE
J 0
(1975 -575);
DISPLAY 0.872340 (1975 -575);
PAINT GREEN (1975 -575);
DISPLAY INVISIBLE (1975 -575);
FORCEPROP 1 LAST OFFPAGE TRUE
J 0
(2325 -600);
DISPLAY 0.872340 (2325 -600);
PAINT GREEN (2325 -600);
DISPLAY INVISIBLE (2325 -600);
FORCEPROP 2 LAST CDS_LIB standard
J 0
(2000 -475);
DISPLAY INVISIBLE (2000 -475);
FORCEPROP 2 LAST PATH I85
J 0
(2200 -425);
DISPLAY 1.021277 (2200 -425);
DISPLAY INVISIBLE (2200 -425);
FORCEADD OFFPAGE..2
(2000 -375);
FORCEPROP 2 LAST $XR0 290 
J 0
(2189 -375);
DISPLAY 0.638298 (2189 -375);
PAINT MONO (2189 -375);
FORCEPROP 1 LAST COMMENT_BODY TRUE
J 0
(1955 -470);
DISPLAY 0.872340 (1955 -470);
PAINT GREEN (1955 -470);
DISPLAY INVISIBLE (1955 -470);
FORCEPROP 1 LAST OFFPAGE TRUE
J 0
(2325 -500);
DISPLAY 0.872340 (2325 -500);
PAINT GREEN (2325 -500);
DISPLAY INVISIBLE (2325 -500);
FORCEPROP 2 LAST CDS_LIB standard
J 0
(2000 -375);
DISPLAY INVISIBLE (2000 -375);
FORCEPROP 2 LAST PATH I86
J 0
(2200 -325);
DISPLAY 1.021277 (2200 -325);
DISPLAY INVISIBLE (2200 -325);
FORCEADD OFFPAGE..4
(2000 -175);
FORCEPROP 2 LAST $XR0 288 
J 0
(2186 -175);
DISPLAY 0.638298 (2186 -175);
PAINT MONO (2186 -175);
FORCEPROP 1 LAST COMMENT_BODY TRUE
J 0
(1975 -275);
DISPLAY 0.872340 (1975 -275);
PAINT GREEN (1975 -275);
DISPLAY INVISIBLE (1975 -275);
FORCEPROP 1 LAST OFFPAGE TRUE
J 0
(2325 -300);
DISPLAY 0.872340 (2325 -300);
PAINT GREEN (2325 -300);
DISPLAY INVISIBLE (2325 -300);
FORCEPROP 2 LAST CDS_LIB standard
J 0
(2000 -175);
DISPLAY INVISIBLE (2000 -175);
FORCEPROP 2 LAST PATH I87
J 0
(2200 -125);
DISPLAY 1.021277 (2200 -125);
DISPLAY INVISIBLE (2200 -125);
FORCEADD OFFPAGE..2
(2000 -75);
FORCEPROP 2 LAST $XR0 288 
J 0
(2189 -75);
DISPLAY 0.638298 (2189 -75);
PAINT MONO (2189 -75);
FORCEPROP 1 LAST COMMENT_BODY TRUE
J 0
(1955 -170);
DISPLAY 0.872340 (1955 -170);
PAINT GREEN (1955 -170);
DISPLAY INVISIBLE (1955 -170);
FORCEPROP 1 LAST OFFPAGE TRUE
J 0
(2325 -200);
DISPLAY 0.872340 (2325 -200);
PAINT GREEN (2325 -200);
DISPLAY INVISIBLE (2325 -200);
FORCEPROP 2 LAST CDS_LIB standard
J 0
(2000 -75);
DISPLAY INVISIBLE (2000 -75);
FORCEPROP 2 LAST PATH I88
J 0
(2200 -25);
DISPLAY 1.021277 (2200 -25);
DISPLAY INVISIBLE (2200 -25);
FORCEADD OFFPAGE..4
(2000 125);
FORCEPROP 2 LAST $XR0 288 
J 0
(2186 125);
DISPLAY 0.638298 (2186 125);
PAINT MONO (2186 125);
FORCEPROP 1 LAST COMMENT_BODY TRUE
J 0
(1975 25);
DISPLAY 0.872340 (1975 25);
PAINT GREEN (1975 25);
DISPLAY INVISIBLE (1975 25);
FORCEPROP 1 LAST OFFPAGE TRUE
J 0
(2325 0);
DISPLAY 0.872340 (2325 0);
PAINT GREEN (2325 0);
DISPLAY INVISIBLE (2325 0);
FORCEPROP 2 LAST CDS_LIB standard
J 0
(2000 125);
DISPLAY INVISIBLE (2000 125);
FORCEPROP 2 LAST PATH I89
J 0
(2200 175);
DISPLAY 1.021277 (2200 175);
DISPLAY INVISIBLE (2200 175);
FORCEADD Q_RES..1
(-2250 -2325);
FORCEPROP 1 LAST PART_NUMBER CS00002JB13
J 0
(-2125 -2375);
DISPLAY 0.510638 (-2125 -2375);
PAINT BLUE (-2125 -2375);
DISPLAY INVISIBLE (-2125 -2375);
FORCEPROP 1 LAST PACK_TYPE 0402LF
J 0
(-2000 -2325);
DISPLAY 0.617021 (-2000 -2325);
PAINT SKYBLUE (-2000 -2325);
FORCEPROP 1 LAST MATERIAL EMPTY
J 0
(-1800 -2325);
DISPLAY 0.617021 (-1800 -2325);
PAINT RED (-1800 -2325);
FORCEPROP 1 LAST TOLERANCE 5%
J 0
(-2075 -2325);
DISPLAY 0.617021 (-2075 -2325);
PAINT SKYBLUE (-2075 -2325);
FORCEPROP 1 LAST VALUE 0
J 2
(-2100 -2325);
DISPLAY 0.617021 (-2100 -2325);
PAINT SKYBLUE (-2100 -2325);
FORCEPROP 1 LAST LOCATION PR304
J 0
(-2475 -2325);
DISPLAY 0.617021 (-2475 -2325);
PAINT AQUA (-2475 -2325);
FORCEPROP 1 LASTPIN (-2350 -2325) $PN 1
J 0
(-2338 -2313);
DISPLAY 0.617021 (-2338 -2313);
PAINT MONO (-2338 -2313);
FORCEPROP 1 LASTPIN (-2150 -2325) $PN 2
J 0
(-2188 -2313);
DISPLAY 0.617021 (-2188 -2313);
PAINT MONO (-2188 -2313);
FORCEPROP 2 LAST CDS_LIB pure_quanta
J 0
(-2250 -2325);
DISPLAY INVISIBLE (-2250 -2325);
FORCEPROP 1 LAST WATTAGE 1/16W
J 2
(-1875 -2425);
DISPLAY 0.510638 (-1875 -2425);
PAINT SKYBLUE (-1875 -2425);
DISPLAY INVISIBLE (-1875 -2425);
FORCEPROP 1 LAST PATH I9
J 0
(-2300 -2175);
DISPLAY 0.978723 (-2300 -2175);
PAINT WHITE (-2300 -2175);
DISPLAY INVISIBLE (-2300 -2175);
FORCEPROP 1 LAST LOCATION PR304
J 0
(-2300 -2225);
DISPLAY 1.021277 (-2300 -2225);
PAINT AQUA (-2300 -2225);
DISPLAY INVISIBLE (-2300 -2225);
FORCEPROP 0 LAST $SEC 1
J 0
(-2300 -2225);
DISPLAY 0.680851 (-2300 -2225);
PAINT MONO (-2300 -2225);
DISPLAY INVISIBLE (-2300 -2225);
FORCEPROP 0 LAST CDS_SEC 1
J 0
(-2300 -2225);
DISPLAY 1.021277 (-2300 -2225);
DISPLAY INVISIBLE (-2300 -2225);
FORCEADD OFFPAGE..4
(2125 -2175);
FORCEPROP 2 LAST $XR3 288 
J 0
(2671 -2175);
DISPLAY 0.638298 (2671 -2175);
PAINT MONO (2671 -2175);
FORCEPROP 2 LAST $XR2 287 
J 0
(2551 -2175);
DISPLAY 0.638298 (2551 -2175);
PAINT MONO (2551 -2175);
FORCEPROP 2 LAST $XR1 286 
J 0
(2431 -2175);
DISPLAY 0.638298 (2431 -2175);
PAINT MONO (2431 -2175);
FORCEPROP 2 LAST $XR0 285 
J 0
(2311 -2175);
DISPLAY 0.638298 (2311 -2175);
PAINT MONO (2311 -2175);
FORCEPROP 1 LAST COMMENT_BODY TRUE
J 0
(2100 -2275);
DISPLAY 0.872340 (2100 -2275);
PAINT GREEN (2100 -2275);
DISPLAY INVISIBLE (2100 -2275);
FORCEPROP 1 LAST OFFPAGE TRUE
J 0
(2450 -2300);
DISPLAY 0.872340 (2450 -2300);
PAINT GREEN (2450 -2300);
DISPLAY INVISIBLE (2450 -2300);
FORCEPROP 2 LAST CDS_LIB standard
J 0
(2125 -2175);
DISPLAY INVISIBLE (2125 -2175);
FORCEPROP 2 LAST PATH I90
J 0
(2675 -2125);
DISPLAY 1.021277 (2675 -2125);
DISPLAY INVISIBLE (2675 -2125);
FORCEADD UNIVERSAL_GND..1
(2875 -2300);
FORCEPROP 3 LASTPIN (2875 -2250) SIG_NAME GND\g
J 0
(2885 -2240);
DISPLAY 0.659574 (2885 -2240);
PAINT MONO (2885 -2240);
DISPLAY INVISIBLE (2885 -2240);
FORCEPROP 1 LAST HDL_POWER GND
J 1
(2900 -2375);
DISPLAY 0.872340 (2900 -2375);
PAINT GREEN (2900 -2375);
DISPLAY INVISIBLE (2900 -2375);
FORCEPROP 2 LAST CDS_LIB logical_power
J 0
(2875 -2300);
DISPLAY INVISIBLE (2875 -2300);
FORCEPROP 1 LAST PATH I91
J 0
(2950 -2300);
DISPLAY 0.872340 (2950 -2300);
PAINT AQUA (2950 -2300);
DISPLAY INVISIBLE (2950 -2300);
FORCEADD Q_CAP..1
(2875 -2075);
FORCEPROP 1 LAST PART_NUMBER TMP_QCH14706KB18
J 0
(2925 -2275);
DISPLAY 0.617021 (2925 -2275);
PAINT BLUE (2925 -2275);
DISPLAY INVISIBLE (2925 -2275);
FORCEPROP 1 LAST VALUE 470PF
J 0
(2925 -2025);
DISPLAY 0.617021 (2925 -2025);
PAINT SKYBLUE (2925 -2025);
FORCEPROP 1 LAST PACK_TYPE 0402
J 0
(2925 -2225);
DISPLAY 0.617021 (2925 -2225);
PAINT SKYBLUE (2925 -2225);
FORCEPROP 1 LAST VOLTAGE 50V
J 0
(2925 -2075);
DISPLAY 0.617021 (2925 -2075);
PAINT SKYBLUE (2925 -2075);
FORCEPROP 1 LAST TOLERANCE 10%
J 0
(2925 -2125);
DISPLAY 0.617021 (2925 -2125);
PAINT SKYBLUE (2925 -2125);
FORCEPROP 1 LAST MATERIAL X7R
J 0
(2925 -2175);
DISPLAY 0.617021 (2925 -2175);
PAINT SKYBLUE (2925 -2175);
FORCEPROP 1 LAST LOCATION PC101
J 0
(2925 -1975);
DISPLAY 0.617021 (2925 -1975);
PAINT AQUA (2925 -1975);
FORCEPROP 1 LASTPIN (2875 -1975) $PN 1
J 0
(2885 -1995);
DISPLAY 0.787234 (2885 -1995);
PAINT MONO (2885 -1995);
FORCEPROP 1 LASTPIN (2875 -2175) $PN 2
J 0
(2885 -2195);
DISPLAY 0.787234 (2885 -2195);
PAINT MONO (2885 -2195);
FORCEPROP 2 LAST CDS_LIB pure_quanta
J 0
(2875 -2075);
DISPLAY INVISIBLE (2875 -2075);
FORCEPROP 1 LAST PATH I92
J 0
(2925 -1925);
DISPLAY 0.978723 (2925 -1925);
PAINT WHITE (2925 -1925);
DISPLAY INVISIBLE (2925 -1925);
FORCEPROP 1 LAST LOCATION PC101
J 0
(2925 -1925);
DISPLAY 1.021277 (2925 -1925);
PAINT AQUA (2925 -1925);
DISPLAY INVISIBLE (2925 -1925);
FORCEPROP 0 LAST $SEC 1
J 0
(2925 -1925);
DISPLAY 0.680851 (2925 -1925);
PAINT MONO (2925 -1925);
DISPLAY INVISIBLE (2925 -1925);
FORCEPROP 0 LAST CDS_SEC 1
J 0
(2925 -1925);
DISPLAY 1.021277 (2925 -1925);
DISPLAY INVISIBLE (2925 -1925);
FORCEADD UNIVERSAL_GND..1
(3575 -2325);
FORCEPROP 3 LASTPIN (3575 -2275) SIG_NAME GND\g
J 0
(3585 -2265);
DISPLAY 0.659574 (3585 -2265);
PAINT MONO (3585 -2265);
DISPLAY INVISIBLE (3585 -2265);
FORCEPROP 1 LAST HDL_POWER GND
J 1
(3600 -2400);
DISPLAY 0.872340 (3600 -2400);
PAINT GREEN (3600 -2400);
DISPLAY INVISIBLE (3600 -2400);
FORCEPROP 2 LAST CDS_LIB logical_power
J 0
(3575 -2325);
PAINT MONO (3575 -2325);
DISPLAY INVISIBLE (3575 -2325);
FORCEPROP 1 LAST PATH I93
J 0
(3650 -2325);
DISPLAY 0.872340 (3650 -2325);
PAINT AQUA (3650 -2325);
DISPLAY INVISIBLE (3650 -2325);
FORCEADD Q_RES..2
(3575 -2100);
FORCEPROP 1 LAST PART_NUMBER CS31002FB08
J 0
(3615 -2225);
DISPLAY 0.638298 (3615 -2225);
DISPLAY INVISIBLE (3615 -2225);
FORCEPROP 1 LAST MATERIAL EMPTY
J 0
(3615 -2175);
DISPLAY 0.638298 (3615 -2175);
PAINT RED (3615 -2175);
FORCEPROP 1 LAST WATTAGE 1/16W
J 0
(3615 -2125);
DISPLAY 0.638298 (3615 -2125);
FORCEPROP 1 LAST VALUE 10K
J 0
(3620 -2025);
DISPLAY 0.638298 (3620 -2025);
FORCEPROP 1 LAST TOLERANCE 1%
J 0
(3620 -2075);
DISPLAY 0.638298 (3620 -2075);
FORCEPROP 1 LAST PACK_TYPE 0402LF
J 0
(3615 -2275);
DISPLAY 0.638298 (3615 -2275);
FORCEPROP 1 LAST LOCATION PR453
J 0
(3620 -1975);
DISPLAY 0.638298 (3620 -1975);
FORCEPROP 1 LASTPIN (3575 -2000) $PN 1
J 0
(3580 -2038);
DISPLAY 0.787234 (3580 -2038);
PAINT MONO (3580 -2038);
FORCEPROP 1 LASTPIN (3575 -2200) $PN 2
J 0
(3580 -2190);
DISPLAY 0.787234 (3580 -2190);
PAINT MONO (3580 -2190);
FORCEPROP 2 LAST CDS_LIB pure_quanta
J 0
(3575 -2100);
DISPLAY INVISIBLE (3575 -2100);
FORCEPROP 1 LAST PATH I94
J 0
(3625 -1925);
DISPLAY 0.978723 (3625 -1925);
PAINT WHITE (3625 -1925);
DISPLAY INVISIBLE (3625 -1925);
FORCEPROP 0 LAST $SEC 1
J 0
(3625 -1925);
DISPLAY 0.680851 (3625 -1925);
PAINT MONO (3625 -1925);
DISPLAY INVISIBLE (3625 -1925);
FORCEPROP 0 LAST CDS_SEC 1
J 0
(3675 -2050);
DISPLAY INVISIBLE (3675 -2050);
FORCEADD OFFPAGE..4
(3825 -1875);
FORCEPROP 2 LAST $XR1 290 
J 0
(4131 -1875);
DISPLAY 0.638298 (4131 -1875);
PAINT MONO (4131 -1875);
FORCEPROP 2 LAST $XR0 289 
J 0
(4011 -1875);
DISPLAY 0.638298 (4011 -1875);
PAINT MONO (4011 -1875);
FORCEPROP 1 LAST COMMENT_BODY TRUE
J 0
(3800 -1975);
DISPLAY 0.872340 (3800 -1975);
PAINT GREEN (3800 -1975);
DISPLAY INVISIBLE (3800 -1975);
FORCEPROP 1 LAST OFFPAGE TRUE
J 0
(4150 -2000);
DISPLAY 0.872340 (4150 -2000);
PAINT GREEN (4150 -2000);
DISPLAY INVISIBLE (4150 -2000);
FORCEPROP 2 LAST CDS_LIB standard
J 0
(3825 -1875);
DISPLAY INVISIBLE (3825 -1875);
FORCEPROP 2 LAST PATH I95
J 0
(4150 -1825);
DISPLAY 1.021277 (4150 -1825);
DISPLAY INVISIBLE (4150 -1825);
FORCEADD OFFPAGE..1
(2975 -1225);
FORCEPROP 2 LAST $XR2 292 
J 0
(2514 -1225);
DISPLAY 0.638298 (2514 -1225);
PAINT MONO (2514 -1225);
FORCEPROP 2 LAST $XR1 284 
J 0
(2634 -1225);
DISPLAY 0.638298 (2634 -1225);
PAINT MONO (2634 -1225);
FORCEPROP 2 LAST $XR0 45 
J 0
(2754 -1225);
DISPLAY 0.638298 (2754 -1225);
PAINT MONO (2754 -1225);
FORCEPROP 1 LAST COMMENT_BODY TRUE
J 0
(3100 -1325);
DISPLAY 0.872340 (3100 -1325);
PAINT GREEN (3100 -1325);
DISPLAY INVISIBLE (3100 -1325);
FORCEPROP 1 LAST OFFPAGE TRUE
J 0
(3300 -1350);
DISPLAY 0.872340 (3300 -1350);
PAINT GREEN (3300 -1350);
DISPLAY INVISIBLE (3300 -1350);
FORCEPROP 2 LAST CDS_LIB standard
J 0
(2975 -1225);
PAINT MONO (2975 -1225);
DISPLAY INVISIBLE (2975 -1225);
FORCEPROP 2 LAST PATH I96
J 0
(2775 -1175);
DISPLAY 1.021277 (2775 -1175);
DISPLAY INVISIBLE (2775 -1175);
FORCEADD OFFPAGE..1
(2975 -925);
FORCEPROP 2 LAST $XR2 292 
J 0
(2514 -925);
DISPLAY 0.638298 (2514 -925);
PAINT MONO (2514 -925);
FORCEPROP 2 LAST $XR1 284 
J 0
(2634 -925);
DISPLAY 0.638298 (2634 -925);
PAINT MONO (2634 -925);
FORCEPROP 2 LAST $XR0 45 
J 0
(2754 -925);
DISPLAY 0.638298 (2754 -925);
PAINT MONO (2754 -925);
FORCEPROP 1 LAST COMMENT_BODY TRUE
J 0
(3100 -1025);
DISPLAY 0.872340 (3100 -1025);
PAINT GREEN (3100 -1025);
DISPLAY INVISIBLE (3100 -1025);
FORCEPROP 1 LAST OFFPAGE TRUE
J 0
(3300 -1050);
DISPLAY 0.872340 (3300 -1050);
PAINT GREEN (3300 -1050);
DISPLAY INVISIBLE (3300 -1050);
FORCEPROP 2 LAST CDS_LIB standard
J 0
(2975 -925);
PAINT MONO (2975 -925);
DISPLAY INVISIBLE (2975 -925);
FORCEPROP 2 LAST PATH I97
J 0
(2775 -875);
DISPLAY 1.021277 (2775 -875);
DISPLAY INVISIBLE (2775 -875);
FORCEADD OFFPAGE..1
(2975 -1075);
FORCEPROP 2 LAST $XR2 292 
J 0
(2514 -1075);
DISPLAY 0.638298 (2514 -1075);
PAINT MONO (2514 -1075);
FORCEPROP 2 LAST $XR1 284 
J 0
(2634 -1075);
DISPLAY 0.638298 (2634 -1075);
PAINT MONO (2634 -1075);
FORCEPROP 2 LAST $XR0 45 
J 0
(2754 -1075);
DISPLAY 0.638298 (2754 -1075);
PAINT MONO (2754 -1075);
FORCEPROP 1 LAST COMMENT_BODY TRUE
J 0
(3100 -1175);
DISPLAY 0.872340 (3100 -1175);
PAINT GREEN (3100 -1175);
DISPLAY INVISIBLE (3100 -1175);
FORCEPROP 1 LAST OFFPAGE TRUE
J 0
(3300 -1200);
DISPLAY 0.872340 (3300 -1200);
PAINT GREEN (3300 -1200);
DISPLAY INVISIBLE (3300 -1200);
FORCEPROP 2 LAST CDS_LIB standard
J 0
(2975 -1075);
PAINT MONO (2975 -1075);
DISPLAY INVISIBLE (2975 -1075);
FORCEPROP 2 LAST PATH I98
J 0
(2775 -1025);
DISPLAY 1.021277 (2775 -1025);
DISPLAY INVISIBLE (2775 -1025);
FORCEADD Q_RES..1
(3925 -925);
FORCEPROP 1 LAST PART_NUMBER CS11002FB07
J 0
(3750 -875);
DISPLAY 0.510638 (3750 -875);
DISPLAY INVISIBLE (3750 -875);
FORCEPROP 1 LAST PACK_TYPE 0402LF
J 0
(3750 -825);
DISPLAY 0.510638 (3750 -825);
FORCEPROP 1 LAST MATERIAL CHIP
J 0
(4250 -925);
DISPLAY 0.638298 (4250 -925);
FORCEPROP 1 LAST TOLERANCE 1%
J 0
(4175 -925);
DISPLAY 0.638298 (4175 -925);
FORCEPROP 1 LAST VALUE 100
J 2
(4125 -925);
DISPLAY 0.638298 (4125 -925);
FORCEPROP 1 LAST WATTAGE 1/16W
J 2
(4075 -825);
DISPLAY 0.510638 (4075 -825);
FORCEPROP 1 LAST LOCATION R2553
J 0
(3700 -925);
DISPLAY 0.638298 (3700 -925);
FORCEPROP 1 LASTPIN (3825 -925) $PN 1
J 0
(3837 -913);
DISPLAY 0.787234 (3837 -913);
PAINT MONO (3837 -913);
FORCEPROP 1 LASTPIN (4025 -925) $PN 2
J 0
(3987 -913);
DISPLAY 0.787234 (3987 -913);
PAINT MONO (3987 -913);
FORCEPROP 2 LAST CDS_LIB pure_quanta
J 0
(3925 -925);
DISPLAY INVISIBLE (3925 -925);
FORCEPROP 1 LAST PATH I99
J 0
(3875 -775);
DISPLAY 0.978723 (3875 -775);
PAINT WHITE (3875 -775);
DISPLAY INVISIBLE (3875 -775);
FORCEPROP 0 LAST $SEC 1
J 0
(4075 -800);
DISPLAY 0.680851 (4075 -800);
PAINT MONO (4075 -800);
DISPLAY INVISIBLE (4075 -800);
FORCEPROP 0 LAST CDS_SEC 1
J 0
(4075 -800);
DISPLAY 1.021277 (4075 -800);
DISPLAY INVISIBLE (4075 -800);
FORCEADD QUANTA_TITLE_BLOCK_C..1
(4675 -3175);
FORCEPROP 0 LAST CDS_CON_LAST_MODIFIED Fri Aug 25 14:04:54 2023
J 0
(2790 -3160);
DISPLAY INVISIBLE (2790 -3160);
FORCEPROP 1 LAST CUSTOM_TXT_CDS <CON_LAST_MODIFIED>
J 0
(2790 -3160);
DISPLAY 0.978723 (2790 -3160);
FORCEPROP 2 LAST CUSTOM_TXT_CDS <XR_PAGE_TITLE>
J 0
(-3215 2075);
DISPLAY 0.638298 (-3215 2075);
PAINT PINK (-3215 2075);
DISPLAY INVISIBLE (-3215 2075);
FORCEPROP 1 LAST CUSTOM_TXT_CDS <NAME_2>
J 0
(1500 -3125);
FORCEPROP 1 LAST CUSTOM_TXT_CDS <NAME_1>
J 0
(1500 -3000);
FORCEPROP 1 LAST CUSTOM_TXT_CDS <Q_NUMBER>
J 0
(3272 -3072);
DISPLAY 1.212766 (3272 -3072);
FORCEPROP 1 LAST CUSTOM_TXT_CDS <Q_PROJ>
J 0
(2293 -3073);
DISPLAY 1.212766 (2293 -3073);
FORCEPROP 1 LAST CUSTOM_TXT_CDS <Q_REV>
J 0
(4491 -3072);
DISPLAY 1.212766 (4491 -3072);
FORCEPROP 1 LAST CUSTOM_TXT_CDS <CON_PAGE_NUM> OF <CON_TOTAL_PAGES>
J 0
(4229 -3157);
DISPLAY 0.978723 (4229 -3157);
FORCEPROP 1 LAST Q_TITLE VCCIN/VCCFA_EHV_FIVRA CPU1 VR(1/7)
J 0
(-4600 -3125);
DISPLAY 2.446809 (-4600 -3125);
PAINT GREEN (-4600 -3125);
FORCEPROP 1 LAST Q_DEPT 
J 1
(912 -3126);
DISPLAY 1.957447 (912 -3126);
PAINT GREEN (912 -3126);
FORCEPROP 2 LAST CDS_XR_PAGE_TITLE CR-284 : @S9S_MB_2U_LIB.S9S_MB_2U(SCH_1):PAGE284
J 0
(-3215 2075);
DISPLAY 0.638298 (-3215 2075);
PAINT PINK (-3215 2075);
DISPLAY INVISIBLE (-3215 2075);
FORCEPROP 2 LAST PAGE_BORDER TRUE
J 0
(-3215 2075);
DISPLAY 0.638298 (-3215 2075);
PAINT PINK (-3215 2075);
DISPLAY INVISIBLE (-3215 2075);
FORCEPROP 1 LAST CDS_LMAN_SYM_OUTLINE -9475,6775,100,-125
J 0
(4675 -3175);
DISPLAY 0.468085 (4675 -3175);
PAINT GREEN (4675 -3175);
DISPLAY INVISIBLE (4675 -3175);
FORCEPROP 2 LAST CDS_LIB pure_quanta
J 0
(4675 -3175);
DISPLAY INVISIBLE (4675 -3175);
FORCEPROP 1 LAST COMMENT_BODY TRUE
J 0
(4687 -3188);
DISPLAY 0.978723 (4687 -3188);
PAINT GREEN (4687 -3188);
DISPLAY INVISIBLE (4687 -3188);
FORCEADD DNS..1
(1125 2825);
PAINT RED (1125 2825);
FORCEPROP 1 LAST COMMENT_BODY TRUE
R 1
J 0
(1200 2600);
DISPLAY 0.872340 (1200 2600);
PAINT GREEN (1200 2600);
DISPLAY INVISIBLE (1200 2600);
FORCEPROP 2 LAST CDS_LIB mstr_misc
J 0
(1125 2825);
DISPLAY INVISIBLE (1125 2825);
FORCEADD DNS..2
(-3075 -2075);
PAINT RED (-3075 -2075);
FORCEPROP 1 LAST COMMENT_BODY TRUE
R 1
J 0
(-3000 -2300);
DISPLAY 0.872340 (-3000 -2300);
PAINT GREEN (-3000 -2300);
DISPLAY INVISIBLE (-3000 -2300);
FORCEPROP 2 LAST CDS_LIB mstr_misc
J 0
(-3075 -2075);
PAINT MONO (-3075 -2075);
DISPLAY INVISIBLE (-3075 -2075);
FORCEADD DNS..2
(-2250 -2300);
PAINT RED (-2250 -2300);
FORCEPROP 1 LAST COMMENT_BODY TRUE
R 1
J 0
(-2175 -2525);
DISPLAY 0.872340 (-2175 -2525);
PAINT GREEN (-2175 -2525);
DISPLAY INVISIBLE (-2175 -2525);
FORCEPROP 2 LAST CDS_LIB mstr_misc
J 0
(-2250 -2300);
DISPLAY INVISIBLE (-2250 -2300);
FORCEADD DNS..1
(-1425 -2625);
PAINT RED (-1425 -2625);
FORCEPROP 1 LAST COMMENT_BODY TRUE
R 1
J 0
(-1350 -2850);
DISPLAY 0.872340 (-1350 -2850);
PAINT GREEN (-1350 -2850);
DISPLAY INVISIBLE (-1350 -2850);
FORCEPROP 2 LAST CDS_LIB mstr_misc
J 0
(-1425 -2625);
DISPLAY INVISIBLE (-1425 -2625);
FORCEADD DNS..1
(-1050 -2650);
PAINT RED (-1050 -2650);
FORCEPROP 1 LAST COMMENT_BODY TRUE
R 1
J 0
(-975 -2875);
DISPLAY 0.872340 (-975 -2875);
PAINT GREEN (-975 -2875);
DISPLAY INVISIBLE (-975 -2875);
FORCEPROP 2 LAST CDS_LIB mstr_misc
J 0
(-1050 -2650);
DISPLAY INVISIBLE (-1050 -2650);
FORCEADD DNS..2
(-1175 -1625);
PAINT RED (-1175 -1625);
FORCEPROP 1 LAST COMMENT_BODY TRUE
R 1
J 0
(-1100 -1850);
DISPLAY 0.872340 (-1100 -1850);
PAINT GREEN (-1100 -1850);
DISPLAY INVISIBLE (-1100 -1850);
FORCEPROP 2 LAST CDS_LIB mstr_misc
J 0
(-1175 -1625);
DISPLAY INVISIBLE (-1175 -1625);
FORCEADD DNS..1
(-1325 3200);
PAINT RED (-1325 3200);
FORCEPROP 1 LAST COMMENT_BODY TRUE
R 1
J 0
(-1250 2975);
DISPLAY 0.872340 (-1250 2975);
PAINT GREEN (-1250 2975);
DISPLAY INVISIBLE (-1250 2975);
FORCEPROP 2 LAST CDS_LIB mstr_misc
J 0
(-1325 3200);
DISPLAY INVISIBLE (-1325 3200);
FORCEADD DNS..1
(1850 -2400);
PAINT RED (1850 -2400);
FORCEPROP 1 LAST COMMENT_BODY TRUE
R 1
J 0
(1925 -2625);
DISPLAY 0.872340 (1925 -2625);
PAINT GREEN (1925 -2625);
DISPLAY INVISIBLE (1925 -2625);
FORCEPROP 2 LAST CDS_LIB mstr_misc
J 0
(1850 -2400);
DISPLAY INVISIBLE (1850 -2400);
FORCEADD DNS..2
(1300 -850);
PAINT RED (1300 -850);
FORCEPROP 1 LAST COMMENT_BODY TRUE
R 1
J 0
(1375 -1075);
DISPLAY 0.872340 (1375 -1075);
PAINT GREEN (1375 -1075);
DISPLAY INVISIBLE (1375 -1075);
FORCEPROP 2 LAST CDS_LIB mstr_misc
J 0
(1300 -850);
DISPLAY INVISIBLE (1300 -850);
FORCEADD DNS..2
(1300 -550);
PAINT RED (1300 -550);
FORCEPROP 1 LAST COMMENT_BODY TRUE
R 1
J 0
(1375 -775);
DISPLAY 0.872340 (1375 -775);
PAINT GREEN (1375 -775);
DISPLAY INVISIBLE (1375 -775);
FORCEPROP 2 LAST CDS_LIB mstr_misc
J 0
(1300 -550);
DISPLAY INVISIBLE (1300 -550);
FORCEADD DNS..1
(3600 -2125);
PAINT RED (3600 -2125);
FORCEPROP 1 LAST COMMENT_BODY TRUE
R 1
J 0
(3675 -2350);
DISPLAY 0.872340 (3675 -2350);
PAINT GREEN (3675 -2350);
DISPLAY INVISIBLE (3675 -2350);
FORCEPROP 2 LAST CDS_LIB mstr_misc
J 0
(3600 -2125);
DISPLAY INVISIBLE (3600 -2125);
FORCEADD DNS..1
(3950 -1225);
PAINT RED (3950 -1225);
FORCEPROP 1 LAST COMMENT_BODY TRUE
R 1
J 0
(4025 -1450);
DISPLAY 0.872340 (4025 -1450);
PAINT GREEN (4025 -1450);
DISPLAY INVISIBLE (4025 -1450);
FORCEPROP 2 LAST CDS_LIB mstr_misc
J 0
(3950 -1225);
PAINT MONO (3950 -1225);
DISPLAY INVISIBLE (3950 -1225);
FORCEADD DNS..1
(3725 -300);
PAINT RED (3725 -300);
FORCEPROP 1 LAST COMMENT_BODY TRUE
R 1
J 0
(3800 -525);
DISPLAY 0.872340 (3800 -525);
PAINT GREEN (3800 -525);
DISPLAY INVISIBLE (3800 -525);
FORCEPROP 2 LAST CDS_LIB mstr_misc
J 0
(3725 -300);
DISPLAY INVISIBLE (3725 -300);
FORCEADD DNS..1
(1475 2825);
PAINT RED (1475 2825);
FORCEPROP 1 LAST COMMENT_BODY TRUE
R 1
J 0
(1550 2600);
DISPLAY 0.872340 (1550 2600);
PAINT GREEN (1550 2600);
DISPLAY INVISIBLE (1550 2600);
FORCEPROP 2 LAST CDS_LIB mstr_misc
J 0
(1475 2825);
DISPLAY INVISIBLE (1475 2825);
WIRE 16 -1 (-2525 -2325)(-2525 -2250);
WIRE 16 -1 (-2525 -2425)(-2525 -2325);
WIRE 16 -1 (-2350 -2325)(-2525 -2325);
WIRE 16 -1 (-2775 -1050)(-2775 -1075);
WIRE 16 -1 (-2475 -1625)(-2475 -1575);
WIRE 16 -1 (-2475 -1625)(-2100 -1625);
WIRE 16 -1 (-2450 -675)(-2450 -625);
WIRE 16 -1 (-2400 -675)(-2450 -675);
WIRE 16 -1 (-2300 175)(-2300 75);
WIRE 16 -1 (-2300 1275)(-2300 1175);
WIRE 16 -1 (-2600 3175)(-2600 3225);
WIRE 16 -1 (-2600 3175)(-2275 3175);
WIRE 16 -1 (4425 -75)(4425 -125);
WIRE 16 -1 (2650 3100)(2650 3025);
WIRE 16 -1 (-2725 -2400)(-2725 -2475);
WIRE 16 -1 (-2600 -600)(-2600 -625);
WIRE 16 -1 (-2600 -600)(-3000 -600);
WIRE 16 -1 (-1475 -2825)(-1475 -2875);
WIRE 16 -1 (-1800 -2825)(-1475 -2825);
WIRE 16 -1 (-1475 -2725)(-1475 -2825);
WIRE 16 -1 (-725 -2825)(-725 -2875);
WIRE 16 -1 (-1050 -2825)(-725 -2825);
WIRE 16 -1 (-725 -2725)(-725 -2825);
WIRE 16 -1 (-575 -2600)(-575 -2525);
WIRE 16 -1 (-1100 -1500)(-550 -1500);
WIRE 16 -1 (-1100 -1625)(-550 -1625);
WIRE 16 -1 (-2325 500)(-2325 450);
WIRE 16 -1 (-2325 500)(-2750 500);
WIRE 16 -1 (-1250 2750)(-675 2750);
WIRE 16 -1 (-1225 3175)(-675 3175);
WIRE 16 -1 (1200 -2550)(1200 -2475);
WIRE 16 -1 (1850 -2575)(1850 -2475);
WIRE 16 -1 (1900 -850)(1900 -875);
WIRE 16 -1 (1375 -850)(1900 -850);
WIRE 16 -1 (1900 -550)(1900 -575);
WIRE 16 -1 (1375 -550)(1900 -550);
WIRE 16 -1 (2875 -2250)(2875 -2175);
WIRE 16 -1 (3575 -2200)(3575 -2275);
WIRE 16 -1 (3700 -550)(3700 -525);
WIRE 16 -1 (2250 2150)(1850 2150);
WIRE 16 -1 (2250 2625)(1850 2625);
WIRE 17 273 (3075 3400)(4646 3400);
WIRE 17 273 (4646 3400)(4646 1870);
WIRE 17 273 (3075 3400)(3075 1870);
WIRE 17 273 (3075 1870)(4646 1870);
WIRE 17 273 (3075 700)(4646 700);
WIRE 17 273 (4646 1800)(4646 700);
WIRE 17 273 (3075 1800)(3075 700);
WIRE 17 273 (3075 1800)(4646 1800);
WIRE 16 -1 (-475 725)(-675 725);
WIRE 16 -1 (-675 650)(-675 725);
WIRE 16 -1 (-1375 750)(-1375 650);
WIRE 16 -1 (-675 650)(-1375 650);
WIRE 16 -1 (-3925 650)(-3100 650);
FORCEPROP 2 LAST SIG_NAME VSENSE_PVCCIN_CPU1_DN
J 0
(-3835 660);
DISPLAY 0.617021 (-3835 660);
WIRE 16 -1 (-3100 650)(-1375 650);
WIRE 16 -1 (-3100 500)(-3100 650);
WIRE 16 -1 (-3100 500)(-2950 500);
WIRE 17 273 (-4175 575)(-3900 575);
WIRE 17 273 (-3900 1125)(-3900 575);
WIRE 17 273 (-4175 575)(-4175 1125);
WIRE 17 273 (-4175 1125)(-3900 1125);
WIRE 16 -1 (875 1625)(1950 1625);
FORCEPROP 2 LAST SIG_NAME PVCCIN_CPU1_IMON2
J 0
(1065 1635);
DISPLAY 0.617021 (1065 1635);
WIRE 16 -1 (875 1725)(1950 1725);
FORCEPROP 2 LAST SIG_NAME PVCCIN_CPU1_PWM2
J 0
(1065 1735);
DISPLAY 0.617021 (1065 1735);
WIRE 16 -1 (-1750 1875)(-475 1875);
FORCEPROP 2 LAST SIG_NAME SMB_CLK_PVCCIN_CPU1
J 0
(-1360 1885);
DISPLAY 0.617021 (-1360 1885);
WIRE 16 -1 (-3150 1875)(-1950 1875);
FORCEPROP 2 LAST SIG_NAME SMB_VR_3V3AUX_SCL_R3
J 0
(-3085 1885);
DISPLAY 0.617021 (-3085 1885);
WIRE 16 2175 (-3150 -875)(-1825 -875);
WIRE 16 2175 (-1825 -775)(-1825 -875);
WIRE 16 2175 (-3150 -775)(-3150 -875);
WIRE 16 2175 (-3150 -775)(-1825 -775);
WIRE 16 -1 (-2200 -975)(-475 -975);
FORCEPROP 2 LAST SIG_NAME PVCCIN_CPU1_VR_FAULT
J 0
(-1435 -965);
DISPLAY 0.617021 (-1435 -965);
WIRE 16 -1 (-2725 -825)(-1900 -825);
FORCEPROP 2 LAST SIG_NAME IRQ_PVCCIN_CPU1_VRHOT_R_N
J 0
(-2735 -815);
DISPLAY 0.617021 (-2735 -815);
WIRE 16 -1 (-1900 -825)(-1750 -825);
WIRE 16 -1 (-1900 -675)(-2200 -675);
WIRE 16 -1 (-1900 -675)(-1900 -825);
WIRE 16 -1 (-1525 -1075)(-2200 -1075);
WIRE 16 -1 (-1525 -1225)(-1525 -1075);
WIRE 16 -1 (-1525 -1225)(-475 -1225);
FORCEPROP 2 LAST SIG_NAME PVCCIN_CPU1_PIN_ALERT
J 0
(-1435 -1215);
DISPLAY 0.617021 (-1435 -1215);
WIRE 16 -1 (-475 -825)(-1550 -825);
FORCEPROP 2 LAST SIG_NAME IRQ_PVCCIN_CPU1_VRHOT_N
J 0
(-1235 -815);
DISPLAY 0.489362 (-1235 -815);
WIRE 16 -1 (-475 -375)(-675 -375);
WIRE 16 -1 (-675 -450)(-675 -375);
WIRE 16 -1 (-1325 -350)(-1325 -450);
WIRE 16 -1 (-675 -450)(-1325 -450);
WIRE 16 -1 (-4000 -450)(-3325 -450);
FORCEPROP 0 LAST SIG_NAME VSENSE_PVCCFA_EHV_FIVRA_CPU1_DN
J 0
(-3910 -440);
DISPLAY 0.489362 (-3910 -440);
WIRE 16 -1 (-1325 -450)(-3325 -450);
WIRE 16 -1 (-3325 -600)(-3200 -600);
WIRE 16 -1 (-3325 -600)(-3325 -450);
WIRE 17 273 (-3950 25)(-3950 -525);
WIRE 17 273 (-4275 25)(-3950 25);
WIRE 17 273 (-4275 -525)(-3950 -525);
WIRE 17 273 (-4275 -525)(-4275 25);
WIRE 17 273 (-4550 -2975)(-2925 -2975);
WIRE 17 273 (-2925 -2750)(-2925 -2975);
WIRE 17 273 (-4550 -2750)(-4550 -2975);
WIRE 17 273 (-4550 -2750)(-2925 -2750);
WIRE 16 -1 (-4050 -2075)(-3200 -2075);
FORCEPROP 2 LAST SIG_NAME PVCCIN_CPU1_VREF
J 0
(-4010 -2065);
DISPLAY 0.617021 (-4010 -2065);
WIRE 16 -1 (-2725 -2200)(-2725 -2075);
WIRE 16 -1 (-2725 -2075)(-475 -2075);
FORCEPROP 2 LAST SIG_NAME PVCCIN_CPU1_ADDR
J 0
(-1435 -2065);
DISPLAY 0.617021 (-1435 -2065);
WIRE 16 -1 (-3000 -2075)(-2725 -2075);
WIRE 16 -1 (-2525 -2425)(-2350 -2425);
WIRE 16 -1 (-3075 75)(-2900 75);
WIRE 16 -1 (-3000 -75)(-3075 -75);
WIRE 16 -1 (-3075 -75)(-3075 75);
WIRE 16 -1 (-4000 -75)(-3075 -75);
FORCEPROP 2 LAST SIG_NAME VSENSE_PVCCFA_EHV_FIVRA_CPU1_DP
J 0
(-3910 -65);
DISPLAY 0.489362 (-3910 -65);
WIRE 16 -1 (-3150 -1375)(-2100 -1375);
FORCEPROP 2 LAST SIG_NAME FM_PVCCFA_EHV_FIVRA_CPU1_EN
J 0
(-3085 -1365);
DISPLAY 0.617021 (-3085 -1365);
WIRE 16 -1 (-2100 -1775)(-3150 -1775);
FORCEPROP 2 LAST SIG_NAME PWRGD_PVCCFA_EHV_FIVRA_CPU1
J 0
(-3085 -1765);
DISPLAY 0.617021 (-3085 -1765);
WIRE 16 -1 (-2300 75)(-2700 75);
WIRE 16 -1 (-2750 -75)(-1875 -75);
FORCEPROP 2 LAST SIG_NAME SH_PVCCFA_EHV_FIVRA_CPU1
J 0
(-2685 -65);
DISPLAY 0.617021 (-2685 -65);
WIRE 16 -1 (-1475 -2525)(-1475 -2325);
WIRE 16 -1 (-1475 -2325)(-475 -2325);
FORCEPROP 2 LAST SIG_NAME PVCCIN_CPU1_CSPIN
J 0
(-1435 -2315);
DISPLAY 0.617021 (-1435 -2315);
WIRE 16 -1 (-1800 -2525)(-1800 -2325);
WIRE 16 -1 (-1475 -2325)(-1800 -2325);
WIRE 16 -1 (-2150 -2325)(-1800 -2325);
WIRE 16 -1 (-1800 -2725)(-1800 -2825);
WIRE 16 -1 (-725 -2525)(-725 -2425);
WIRE 16 -1 (-725 -2425)(-475 -2425);
WIRE 16 -1 (-1050 -2525)(-1050 -2425);
WIRE 16 -1 (-1050 -2425)(-725 -2425);
WIRE 16 -1 (-2150 -2425)(-1050 -2425);
FORCEPROP 2 LAST SIG_NAME PVCCIN_CPU1_VIN_CSNIN
J 0
(-1435 -2415);
DISPLAY 0.617021 (-1435 -2415);
WIRE 16 -1 (-1050 -2725)(-1050 -2825);
WIRE 16 -1 (-475 -2525)(-575 -2525);
WIRE 16 -1 (-1900 -1775)(-1525 -1775);
WIRE 16 -1 (-1525 -1775)(-475 -1775);
FORCEPROP 2 LAST SIG_NAME PWRGD_PVCCFA_EHV_FIVRA_CPU1_R
J 0
(-1435 -1765);
DISPLAY 0.617021 (-1435 -1765);
WIRE 16 -1 (-1525 -1625)(-1900 -1625);
WIRE 16 -1 (-1525 -1625)(-1525 -1775);
WIRE 16 -1 (-1300 -1625)(-1525 -1625);
WIRE 16 -1 (-675 -125)(-475 -125);
WIRE 16 -1 (-675 -75)(-675 -125);
WIRE 16 -1 (-1325 -150)(-1325 -75);
WIRE 16 -1 (-675 -75)(-1325 -75);
FORCEPROP 2 LAST SIG_NAME SH_PVCCFA_EHV_FIVRA_CPU1_R
J 0
(-1310 -65);
DISPLAY 0.617021 (-1310 -65);
WIRE 16 -1 (-1675 -75)(-1325 -75);
WIRE 16 -1 (-3100 1175)(-2900 1175);
WIRE 16 -1 (-3100 1025)(-3100 1175);
WIRE 16 -1 (-3000 1025)(-3100 1025);
WIRE 16 -1 (-3925 1025)(-3100 1025);
FORCEPROP 2 LAST SIG_NAME VSENSE_PVCCIN_CPU1_DP
J 0
(-3835 1035);
DISPLAY 0.617021 (-3835 1035);
WIRE 16 -1 (-2300 1175)(-2700 1175);
WIRE 16 -1 (-3325 2275)(-2275 2275);
FORCEPROP 2 LAST SIG_NAME SVID_ALERT0_CPU1_R_N
J 0
(-3235 2285);
DISPLAY 0.617021 (-3235 2285);
WIRE 16 -1 (-3325 3025)(-2275 3025);
FORCEPROP 2 LAST SIG_NAME PWRGD_PVCCIN_CPU1
J 0
(-3235 3035);
DISPLAY 0.617021 (-3235 3035);
WIRE 16 -1 (-3325 2875)(-2275 2875);
FORCEPROP 2 LAST SIG_NAME FM_PVCCIN_CPU1_EN
J 0
(-3235 2885);
DISPLAY 0.617021 (-3235 2885);
WIRE 16 -1 (-3325 2575)(-2275 2575);
FORCEPROP 2 LAST SIG_NAME SVID_CLK0_CPU1_R
J 0
(-3235 2585);
DISPLAY 0.617021 (-3235 2585);
WIRE 16 -1 (-2275 2425)(-3325 2425);
FORCEPROP 2 LAST SIG_NAME SVID_DIO0_CPU1_R
J 0
(-3235 2435);
DISPLAY 0.617021 (-3235 2435);
WIRE 16 -1 (-1650 3175)(-2075 3175);
WIRE 16 -1 (-1425 3175)(-1650 3175);
WIRE 16 -1 (-1650 3025)(-2075 3025);
WIRE 16 -1 (-1650 3025)(-1650 3175);
WIRE 16 -1 (-1650 3025)(-475 3025);
FORCEPROP 2 LAST SIG_NAME PWRGD_PVCCIN_CPU1_R
J 0
(-1510 3035);
DISPLAY 0.617021 (-1510 3035);
WIRE 16 -1 (-2075 2575)(-475 2575);
FORCEPROP 2 LAST SIG_NAME SVID_CLK_PVCCIN_CPU1_R
J 0
(-1510 2585);
DISPLAY 0.617021 (-1510 2585);
WIRE 16 -1 (-2075 2425)(-475 2425);
FORCEPROP 2 LAST SIG_NAME SVID_DIO_PVCCIN_CPU1_R
J 0
(-1510 2435);
DISPLAY 0.617021 (-1510 2435);
WIRE 16 -1 (-2075 2275)(-475 2275);
FORCEPROP 2 LAST SIG_NAME SVID_ALERT_PVCCIN_CPU1_R
J 0
(-1510 2285);
DISPLAY 0.617021 (-1510 2285);
WIRE 16 -1 (-1950 1725)(-3150 1725);
FORCEPROP 2 LAST SIG_NAME SMB_VR_3V3AUX_SDA_R3
J 0
(-3085 1735);
DISPLAY 0.617021 (-3085 1735);
WIRE 16 -1 (-1450 1575)(-475 1575);
FORCEPROP 2 LAST SIG_NAME NC_PVCCIN_CPU1_SMB_ALERT
J 0
(-1360 1585);
DISPLAY 0.617021 (-1360 1585);
WIRE 16 -1 (-1750 1725)(-475 1725);
FORCEPROP 2 LAST SIG_NAME SMB_DIO_PVCCIN_CPU1
J 0
(-1360 1735);
DISPLAY 0.617021 (-1360 1735);
WIRE 16 -1 (-1450 2750)(-1650 2750);
WIRE 16 -1 (-1650 2875)(-1650 2750);
WIRE 16 -1 (-1650 2875)(-475 2875);
FORCEPROP 2 LAST SIG_NAME PVCCIN_CPU1_EN_R
J 0
(-1510 2885);
DISPLAY 0.617021 (-1510 2885);
WIRE 16 -1 (-2075 2875)(-1650 2875);
WIRE 16 -1 (1200 -2175)(875 -2175);
WIRE 16 -1 (1200 -2175)(1200 -2275);
WIRE 16 -1 (1850 -2175)(1200 -2175);
FORCEPROP 2 LAST SIG_NAME PVCCIN_CPU1_ATSEN
J 0
(1315 -2165);
DISPLAY 0.617021 (1315 -2165);
WIRE 16 -1 (1850 -2275)(1850 -2175);
WIRE 16 -1 (2075 -2175)(1850 -2175);
WIRE 16 -1 (875 -375)(1950 -375);
FORCEPROP 2 LAST SIG_NAME PVCCFA_EHV_FIVRA_CPU1_PWM4
J 0
(1065 -365);
DISPLAY 0.617021 (1065 -365);
WIRE 16 -1 (875 -1275)(1950 -1275);
FORCEPROP 2 LAST SIG_NAME PVCCFA_EHV_FIVRA_CPU1_PWM1
J 0
(1065 -1265);
DISPLAY 0.617021 (1065 -1265);
WIRE 16 -1 (875 -75)(1950 -75);
FORCEPROP 2 LAST SIG_NAME PVCCIN_CPU1_PWM8
J 0
(1065 -65);
DISPLAY 0.617021 (1065 -65);
WIRE 16 -1 (875 -175)(1950 -175);
FORCEPROP 2 LAST SIG_NAME PVCCIN_CPU1_IMON8
J 0
(1065 -165);
DISPLAY 0.617021 (1065 -165);
WIRE 16 -1 (875 125)(1950 125);
FORCEPROP 2 LAST SIG_NAME PVCCIN_CPU1_IMON7
J 0
(1065 135);
DISPLAY 0.617021 (1065 135);
WIRE 16 -1 (1950 -1375)(875 -1375);
FORCEPROP 2 LAST SIG_NAME PVCCFA_EHV_FIVRA_CPU1_IMON1
J 0
(1065 -1365);
DISPLAY 0.617021 (1065 -1365);
WIRE 16 -1 (1950 -1075)(875 -1075);
FORCEPROP 2 LAST SIG_NAME PVCCFA_EHV_FIVRA_CPU1_IMON2
J 0
(1065 -1065);
DISPLAY 0.617021 (1065 -1065);
WIRE 16 -1 (875 -975)(1950 -975);
FORCEPROP 2 LAST SIG_NAME PVCCFA_EHV_FIVRA_CPU1_PWM2
J 0
(1065 -965);
DISPLAY 0.617021 (1065 -965);
WIRE 16 -1 (875 -675)(1950 -675);
FORCEPROP 0 LAST SIG_NAME PVCCFA_EHV_FIVRA_CPU1_PWM3
J 0
(1065 -665);
DISPLAY 0.617021 (1065 -665);
WIRE 16 -1 (1025 -850)(1175 -850);
WIRE 16 -1 (1025 -775)(875 -775);
WIRE 16 -1 (1025 -775)(1025 -850);
WIRE 16 -1 (1950 -775)(1025 -775);
FORCEPROP 2 LAST SIG_NAME PVCCFA_EHV_FIVRA_CPU1_IMON3
J 0
(1065 -765);
DISPLAY 0.617021 (1065 -765);
WIRE 16 -1 (1025 -550)(1175 -550);
WIRE 16 -1 (1025 -475)(875 -475);
WIRE 16 -1 (1025 -475)(1025 -550);
WIRE 16 -1 (1950 -475)(1025 -475);
FORCEPROP 2 LAST SIG_NAME PVCCFA_EHV_FIVRA_CPU1_IMON4
J 0
(1065 -465);
DISPLAY 0.617021 (1065 -465);
WIRE 16 -1 (3575 -2000)(3575 -1875);
WIRE 16 -1 (3775 -1875)(3575 -1875);
WIRE 16 -1 (2875 -1875)(2875 -1975);
WIRE 16 -1 (3575 -1875)(2875 -1875);
FORCEPROP 2 LAST SIG_NAME PVCCFA_EHV_FIVRA_CPU1_BTSEN
J 0
(2015 -1865);
DISPLAY 0.617021 (2015 -1865);
WIRE 16 -1 (875 -1875)(2875 -1875);
WIRE 16 -1 (3025 -925)(3825 -925);
FORCEPROP 0 LAST CDS_PHYS_NET_NAME SVID_DIO0_CPU1_R
J 0
(3340 -877);
PAINT MONO (3340 -877);
DISPLAY INVISIBLE (3340 -877);
FORCEPROP 2 LAST SIG_NAME SVID_DIO0_CPU1_R
J 0
(3090 -915);
DISPLAY 0.489362 (3090 -915);
WIRE 16 -1 (3025 -1075)(3825 -1075);
FORCEPROP 0 LAST CDS_PHYS_NET_NAME SVID_CLK0_CPU1_R
J 0
(3065 -1027);
PAINT MONO (3065 -1027);
DISPLAY INVISIBLE (3065 -1027);
FORCEPROP 2 LAST SIG_NAME SVID_CLK0_CPU1_R
J 0
(3090 -1065);
DISPLAY 0.489362 (3090 -1065);
WIRE 16 -1 (3025 -1225)(3825 -1225);
FORCEPROP 0 LAST CDS_PHYS_NET_NAME SVID_ALERT0_CPU1_R_N
J 0
(3440 -1177);
PAINT MONO (3440 -1177);
DISPLAY INVISIBLE (3440 -1177);
FORCEPROP 2 LAST SIG_NAME SVID_ALERT0_CPU1_R_N
J 0
(3090 -1215);
DISPLAY 0.489362 (3090 -1215);
WIRE 16 -1 (4025 -425)(4025 -525);
WIRE 16 -1 (3700 -525)(4025 -525);
WIRE 16 -1 (3700 -400)(3700 -525);
WIRE 16 -1 (3700 -200)(3700 -125);
WIRE 16 -1 (4025 -125)(3700 -125);
WIRE 16 -1 (4025 -225)(4025 -125);
WIRE 16 -1 (4425 -1225)(4025 -1225);
WIRE 16 -1 (4425 -125)(4025 -125);
WIRE 16 -1 (4425 -925)(4025 -925);
WIRE 16 -1 (4425 -125)(4425 -925);
WIRE 16 -1 (4425 -1075)(4025 -1075);
WIRE 16 -1 (4425 -1075)(4425 -1225);
WIRE 16 -1 (4425 -1075)(4425 -925);
WIRE 16 -1 (875 525)(1950 525);
FORCEPROP 2 LAST SIG_NAME PVCCIN_CPU1_PWM6
J 0
(1065 535);
DISPLAY 0.617021 (1065 535);
WIRE 16 -1 (875 725)(1950 725);
FORCEPROP 2 LAST SIG_NAME PVCCIN_CPU1_IMON5
J 0
(1065 735);
DISPLAY 0.617021 (1065 735);
WIRE 16 -1 (875 825)(1950 825);
FORCEPROP 0 LAST SIG_NAME PVCCIN_CPU1_PWM5
J 0
(1065 835);
DISPLAY 0.617021 (1065 835);
WIRE 16 -1 (875 225)(1950 225);
FORCEPROP 2 LAST SIG_NAME PVCCIN_CPU1_PWM7
J 0
(1065 235);
DISPLAY 0.617021 (1065 235);
WIRE 16 -1 (875 2025)(1950 2025);
FORCEPROP 2 LAST SIG_NAME PVCCIN_CPU1_PWM1
J 0
(1065 2035);
DISPLAY 0.617021 (1065 2035);
WIRE 16 -1 (875 1925)(1950 1925);
FORCEPROP 2 LAST SIG_NAME PVCCIN_CPU1_IMON1
J 0
(1065 1935);
DISPLAY 0.617021 (1065 1935);
WIRE 16 -1 (875 425)(1950 425);
FORCEPROP 2 LAST SIG_NAME PVCCIN_CPU1_IMON6
J 0
(1065 435);
DISPLAY 0.617021 (1065 435);
WIRE 16 -1 (875 1125)(1950 1125);
FORCEPROP 2 LAST SIG_NAME PVCCIN_CPU1_PWM4
J 0
(1065 1135);
DISPLAY 0.617021 (1065 1135);
WIRE 16 -1 (875 1425)(1950 1425);
FORCEPROP 2 LAST SIG_NAME PVCCIN_CPU1_PWM3
J 0
(1065 1435);
DISPLAY 0.617021 (1065 1435);
WIRE 16 -1 (875 1025)(1950 1025);
FORCEPROP 2 LAST SIG_NAME PVCCIN_CPU1_IMON4
J 0
(1065 1035);
DISPLAY 0.617021 (1065 1035);
WIRE 16 -1 (1850 2150)(1850 2250);
WIRE 16 -1 (1450 2150)(1850 2150);
WIRE 16 -1 (1450 2250)(1450 2150);
WIRE 16 -1 (2650 3025)(2275 3025);
WIRE 16 -1 (-2750 1025)(-1925 1025);
FORCEPROP 2 LAST SIG_NAME SH_PVCCIN_CPU1
J 0
(-2585 1035);
DISPLAY 0.617021 (-2585 1035);
WIRE 16 -1 (-1375 950)(-1375 1025);
WIRE 16 -1 (-1725 1025)(-1375 1025);
WIRE 16 -1 (-675 1025)(-1375 1025);
FORCEPROP 2 LAST SIG_NAME SH_PVCCIN_CPU1_R
J 0
(-1285 1035);
DISPLAY 0.617021 (-1285 1035);
WIRE 16 -1 (-675 1025)(-675 975);
WIRE 16 -1 (-475 975)(-675 975);
WIRE 16 -1 (875 1325)(1950 1325);
FORCEPROP 2 LAST SIG_NAME PVCCIN_CPU1_IMON3
J 0
(1065 1335);
DISPLAY 0.617021 (1065 1335);
WIRE 16 -1 (875 2725)(1025 2725);
WIRE 16 -1 (1025 2725)(1025 2550);
WIRE 16 -1 (1450 2550)(1025 2550);
FORCEPROP 2 LAST SIG_NAME PVCCIN_CPU1_VREF
J 0
(1065 2560);
DISPLAY 0.617021 (1065 2560);
WIRE 16 -1 (1450 2450)(1450 2550);
WIRE 16 -1 (1850 2550)(1450 2550);
WIRE 16 -1 (1850 2550)(1850 2450);
WIRE 16 -1 (2225 2550)(1850 2550);
WIRE 16 -1 (875 3025)(1100 3025);
FORCEPROP 2 LAST SIG_NAME PVCCIN_CPU1_VCC
J 0
(1065 3035);
DISPLAY 0.617021 (1065 3035);
WIRE 16 -1 (1100 2925)(1100 3025);
WIRE 16 -1 (1100 3025)(1450 3025);
WIRE 16 -1 (1450 2925)(1450 3025);
WIRE 16 -1 (1450 3025)(1850 3025);
WIRE 16 -1 (2075 3025)(1850 3025);
WIRE 16 -1 (1850 2925)(1850 3025);
WIRE 16 -1 (1100 2725)(1100 2625);
WIRE 16 -1 (1100 2625)(1450 2625);
WIRE 16 -1 (1450 2725)(1450 2625);
WIRE 16 -1 (1450 2625)(1850 2625);
WIRE 16 -1 (1850 2725)(1850 2625);
WIRE 16 -1 (-2775 -1075)(-2600 -1075);
WIRE 16 -1 (-2400 -1075)(-2600 -1075);
WIRE 16 -1 (-2600 -975)(-2600 -1075);
WIRE 16 -1 (-2400 -975)(-2600 -975);
WIRE 16 -1 (-1900 -1375)(-1525 -1375);
WIRE 16 -1 (-1525 -1375)(-475 -1375);
FORCEPROP 2 LAST SIG_NAME PVCCFA_EHV_FIVRA_CPU1_EN_R
J 0
(-1435 -1365);
DISPLAY 0.617021 (-1435 -1365);
WIRE 16 -1 (-1525 -1375)(-1525 -1500);
WIRE 16 -1 (-1525 -1500)(-1300 -1500);
DOT 1 (-1375 650);
DOT 1 (-2725 -2075);
DOT 1 (-2525 -2325);
DOT 1 (-3325 -450);
DOT 1 (-3075 -75);
DOT 1 (-2600 -1075);
DOT 1 (-1800 -2325);
DOT 1 (-1475 -2825);
DOT 1 (-1050 -2425);
DOT 1 (-1475 -2325);
DOT 1 (-725 -2825);
DOT 1 (-725 -2425);
DOT 1 (-1525 -1775);
DOT 1 (-1525 -1625);
DOT 1 (-1325 -450);
DOT 1 (-1325 -75);
DOT 1 (-3100 650);
DOT 1 (-3100 1025);
DOT 1 (-1375 1025);
DOT 1 (-1650 2875);
DOT 1 (-1650 3175);
DOT 1 (-1650 3025);
DOT 1 (1200 -2175);
DOT 1 (1850 -2175);
DOT 1 (1025 -775);
DOT 1 (1025 -475);
DOT 1 (2875 -1875);
DOT 1 (3575 -1875);
DOT 1 (3700 -525);
DOT 1 (4025 -125);
DOT 1 (4425 -1075);
DOT 1 (4425 -925);
DOT 1 (4425 -125);
DOT 1 (1850 2150);
DOT 1 (1450 2550);
DOT 1 (1450 3025);
DOT 1 (1850 2550);
DOT 1 (1850 2625);
DOT 1 (1850 3025);
DOT 1 (1100 3025);
DOT 1 (1450 2625);
DOT 1 (-1525 -1375);
DOT 1 (-1900 -825);
FORCENOTE
LOAD-LINE=0.5 MOHM
(3100 2295) 0;
DISPLAY LEFT (3100 2295);
DISPLAY 0.936170 (3100 2295);
PAINT WHITE (3100 2295);
FORCENOTE
1081A(UNDERSHOOT)
(3100 2370) 0;
DISPLAY LEFT (3100 2370);
DISPLAY 0.936170 (3100 2370);
PAINT RED (3100 2370);
FORCENOTE
SLEW RATE=960A/US(OVERSHOOT)
(3095 2458) 0;
DISPLAY LEFT (3095 2458);
DISPLAY 0.936170 (3095 2458);
PAINT WHITE (3095 2458);
FORCENOTE
442A(UNDERSHOOT)
(3100 2545) 0;
DISPLAY LEFT (3100 2545);
DISPLAY 0.936170 (3100 2545);
PAINT RED (3100 2545);
FORCENOTE
CURRENT STEP=370A(OVERSHOOT)
(3100 2620) 0;
DISPLAY LEFT (3100 2620);
DISPLAY 0.936170 (3100 2620);
PAINT RED (3100 2620);
FORCENOTE
TRANSIENT OCP=600A
(3550 2700) 0;
DISPLAY LEFT (3550 2700);
DISPLAY 0.936170 (3550 2700);
PAINT WHITE (3550 2700);
FORCENOTE
VBOOT=1.8V
(3125 1617) 0;
DISPLAY LEFT (3125 1617);
DISPLAY 0.936170 (3125 1617);
PAINT WHITE (3125 1617);
FORCENOTE
PVCCFA_EHV_FIVRA_CPU0 SPECIFICATION
(3125 1725) 0;
DISPLAY LEFT (3125 1725);
DISPLAY 0.808511 (3125 1725);
PAINT WHITE (3125 1725);
FORCENOTE
PVCCIN_CPU1 SPECIFICATION
(3100 3317) 0;
DISPLAY LEFT (3100 3317);
DISPLAY 1.170213 (3100 3317);
PAINT WHITE (3100 3317);
FORCENOTE
VBOOT=1.8V
(3100 3217) 0;
DISPLAY LEFT (3100 3217);
DISPLAY 0.936170 (3100 3217);
PAINT WHITE (3100 3217);
FORCENOTE
VID=1.6V~1.88V(TYP=1.8 OR1.83V)
(3100 3142) 0;
DISPLAY LEFT (3100 3142);
DISPLAY 0.936170 (3100 3142);
PAINT WHITE (3100 3142);
FORCENOTE
RIPPLE=+/-10MV
(3100 3067) 0;
DISPLAY LEFT (3100 3067);
DISPLAY 0.936170 (3100 3067);
PAINT WHITE (3100 3067);
FORCENOTE
DC=+/-0.5%
(3100 2992) 0;
DISPLAY LEFT (3100 2992);
DISPLAY 0.936170 (3100 2992);
PAINT WHITE (3100 2992);
FORCENOTE
TOTAL TOLERANCE BAND=+/-22MV
(3100 2916) 0;
DISPLAY LEFT (3100 2916);
DISPLAY 0.936170 (3100 2916);
PAINT WHITE (3100 2916);
FORCENOTE
TDC=220A
(3100 2855) 0;
DISPLAY LEFT (3100 2855);
DISPLAY 0.936170 (3100 2855);
PAINT RED (3100 2855);
FORCENOTE
ICCIN_MAX.APP=430A
(3100 2780) 0;
DISPLAY LEFT (3100 2780);
DISPLAY 0.936170 (3100 2780);
PAINT RED (3100 2780);
FORCENOTE
PDG REV 1.6 FOR 350W SPR+HBM
(3100 1895) 0;
DISPLAY LEFT (3100 1895);
DISPLAY 0.936170 (3100 1895);
PAINT RED (3100 1895);
FORCENOTE
SETVID RATE=25MV/US (FAST)
(3100 1970) 0;
DISPLAY LEFT (3100 1970);
DISPLAY 0.936170 (3100 1970);
PAINT WHITE (3100 1970);
FORCENOTE
PROTOCOL ID=0AH (VR14 10MV VID)
(3095 2058) 0;
DISPLAY LEFT (3095 2058);
DISPLAY 0.936170 (3095 2058);
PAINT WHITE (3095 2058);
FORCENOTE
SVID ADDRESS=00H BUS#0
(3100 2145) 0;
DISPLAY LEFT (3100 2145);
DISPLAY 0.936170 (3100 2145);
PAINT WHITE (3100 2145);
FORCENOTE
WORK FREQUENCY=700KHZ
(3100 2220) 0;
DISPLAY LEFT (3100 2220);
DISPLAY 0.936170 (3100 2220);
PAINT WHITE (3100 2220);
FORCENOTE
PROTOCOL ID=04H (VR13 10MV VID)
(3125 875) 0;
DISPLAY LEFT (3125 875);
DISPLAY 0.936170 (3125 875);
PAINT WHITE (3125 875);
FORCENOTE
SETVID RATE=10MV/US (FAST)
(3125 800) 0;
DISPLAY LEFT (3125 800);
DISPLAY 0.936170 (3125 800);
PAINT WHITE (3125 800);
FORCENOTE
20220808 UPDATE PDG REV 1.6
(2650 600) 0;
DISPLAY LEFT (2650 600);
DISPLAY 1.595745 (2650 600);
FORCENOTE
OCP=500A
(3100 2700) 0;
DISPLAY LEFT (3100 2700);
DISPLAY 0.936170 (3100 2700);
PAINT WHITE (3100 2700);
FORCENOTE
PDG REV.1.6 FOR SPR+HBM
(3125 725) 0;
DISPLAY LEFT (3125 725);
DISPLAY 0.936170 (3125 725);
PAINT RED (3125 725);
FORCENOTE
VID=1.6V~1.88V(TYP=1.8V)
(3125 1542) 0;
DISPLAY LEFT (3125 1542);
DISPLAY 0.936170 (3125 1542);
PAINT WHITE (3125 1542);
FORCENOTE
RIPPLE=+/-9MV
(3125 1467) 0;
DISPLAY LEFT (3125 1467);
DISPLAY 0.936170 (3125 1467);
PAINT WHITE (3125 1467);
FORCENOTE
TDC=102A
(3125 1325) 0;
DISPLAY LEFT (3125 1325);
DISPLAY 0.936170 (3125 1325);
PAINT WHITE (3125 1325);
FORCENOTE
OCP=164A
(3125 1175) 0;
DISPLAY LEFT (3125 1175);
DISPLAY 0.936170 (3125 1175);
PAINT WHITE (3125 1175);
FORCENOTE
SVID ADDRESS=03H BUS#0
(3125 950) 0;
DISPLAY LEFT (3125 950);
DISPLAY 0.936170 (3125 950);
PAINT WHITE (3125 950);
FORCENOTE
WORK FREQUENCY=700KHZ
(3125 1025) 0;
DISPLAY LEFT (3125 1025);
DISPLAY 0.936170 (3125 1025);
PAINT WHITE (3125 1025);
FORCENOTE
LOAD-LINE=0.7 MOHM
(3125 1100) 0;
DISPLAY LEFT (3125 1100);
DISPLAY 0.936170 (3125 1100);
PAINT WHITE (3125 1100);
FORCENOTE
MAX CURRENT=136A
(3125 1250) 0;
DISPLAY LEFT (3125 1250);
DISPLAY 0.936170 (3125 1250);
PAINT WHITE (3125 1250);
FORCENOTE
DC=+/-0.5% OF VID
(3125 1395) 0;
DISPLAY LEFT (3125 1395);
DISPLAY 0.936170 (3125 1395);
PAINT WHITE (3125 1395);
FORCENOTE
PVCCIN_CPU1
(-4446 -2925) 0;
DISPLAY LEFT (-4446 -2925);
DISPLAY 0.638298 (-4446 -2925);
PAINT WHITE (-4446 -2925);
FORCENOTE
RAIL
(-4371 -2825) 0;
DISPLAY LEFT (-4371 -2825);
DISPLAY 0.808511 (-4371 -2825);
PAINT WHITE (-4371 -2825);
FORCENOTE
SVID / I2C ADDRESS
(-4471 -2700) 0;
DISPLAY LEFT (-4471 -2700);
DISPLAY 1.170213 (-4471 -2700);
PAINT WHITE (-4471 -2700);
FORCENOTE
TRACE SPACING = 5MIL
(-4300 -775) 0;
DISPLAY LEFT (-4300 -775);
DISPLAY 1.021277 (-4300 -775);
PAINT WHITE (-4300 -775);
FORCENOTE
TRACE WIDTH = 10MIL
(-4300 -700) 0;
DISPLAY LEFT (-4300 -700);
DISPLAY 1.021277 (-4300 -700);
PAINT WHITE (-4300 -700);
FORCENOTE
DIFFERENTIAL PAIR
(-4300 -625) 0;
DISPLAY LEFT (-4300 -625);
DISPLAY 1.021277 (-4300 -625);
PAINT WHITE (-4300 -625);
FORCENOTE
00H
(-3971 -2925) 0;
DISPLAY LEFT (-3971 -2925);
DISPLAY 0.638298 (-3971 -2925);
PAINT WHITE (-3971 -2925);
FORCENOTE
72H/E4H
(-3646 -2925) 0;
DISPLAY LEFT (-3646 -2925);
DISPLAY 0.638298 (-3646 -2925);
PAINT WHITE (-3646 -2925);
FORCENOTE
SVID
(-3996 -2825) 0;
DISPLAY LEFT (-3996 -2825);
DISPLAY 0.808511 (-3996 -2825);
PAINT WHITE (-3996 -2825);
FORCENOTE
I2C(7BIT/8BIT)
(-3646 -2825) 0;
DISPLAY LEFT (-3646 -2825);
DISPLAY 0.808511 (-3646 -2825);
PAINT WHITE (-3646 -2825);
FORCENOTE
CONFIRM ADDRESS SETTING
(-2450 -2000) 0;
DISPLAY LEFT (-2450 -2000);
DISPLAY 1.021277 (-2450 -2000);
PAINT SKYBLUE (-2450 -2000);
FORCENOTE
TRACE WIDTH = 10MIL
(-4175 375) 0;
DISPLAY LEFT (-4175 375);
DISPLAY 1.021277 (-4175 375);
PAINT WHITE (-4175 375);
FORCENOTE
DIFFERENTIAL PAIR
(-4175 450) 0;
DISPLAY LEFT (-4175 450);
DISPLAY 1.021277 (-4175 450);
PAINT WHITE (-4175 450);
FORCENOTE
20211013 MODIFY FOR GT
(-4625 3300) 0;
DISPLAY LEFT (-4625 3300);
DISPLAY 1.595745 (-4625 3300);
PAINT PINK (-4625 3300);
FORCENOTE
TRACE SPACING = 5MIL
(-4175 300) 0;
DISPLAY LEFT (-4175 300);
DISPLAY 1.021277 (-4175 300);
PAINT WHITE (-4175 300);
FORCENOTE
20220725 CONNECT TO CPLD
(-3175 -750) 0;
DISPLAY LEFT (-3175 -750);
DISPLAY 0.680851 (-3175 -750);
PAINT WHITE (-3175 -750);
QUIT
